FILE_TYPE = MACRO_DRAWING;
SET COLOR_WIRE YELLOW;
SET COLOR_PROP ORANGE;
SET COLOR_DOT WHITE;
SET COLOR_ARC YELLOW;
SET COLOR_BODY GREEN;
SET COLOR_NOTE PURPLE;
SET PROP_DISPLAY VALUE;
SET PAGE_NUMBER P89;
FORCEADD GND..1
(-2300 2175);
FORCEPROP 3 LASTPIN (-2300 2225) SIG_NAME GND\g
J 0
(-2290 2235);
DISPLAY 0.659574 (-2290 2235);
PAINT MONO (-2290 2235);
DISPLAY INVISIBLE (-2290 2235);
FORCEPROP 2 LAST CDS_LIB mstr_symbols
J 0
(-2300 2175);
DISPLAY 0.723404 (-2300 2175);
DISPLAY INVISIBLE (-2300 2175);
FORCEPROP 1 LAST SIZE 1B
J 0
(-2225 2125);
DISPLAY 0.851064 (-2225 2125);
PAINT GREEN (-2225 2125);
DISPLAY INVISIBLE (-2225 2125);
FORCEPROP 1 LAST BODY_TYPE PLUMBING
J 0
(-2345 2132);
DISPLAY 0.340426 (-2345 2132);
PAINT GREEN (-2345 2132);
DISPLAY INVISIBLE (-2345 2132);
FORCEPROP 1 LAST PATH I150
J 0
(-2225 2175);
DISPLAY 0.872340 (-2225 2175);
PAINT GREEN (-2225 2175);
DISPLAY INVISIBLE (-2225 2175);
FORCEPROP 1 LAST VOLTAGE 0.0
J 0
(-2345 2132);
DISPLAY 0.723404 (-2345 2132);
PAINT SKYBLUE (-2345 2132);
DISPLAY INVISIBLE (-2345 2132);
FORCEPROP 1 LAST HDL_POWER GND
J 0
(-2300 2325);
DISPLAY 0.851064 (-2300 2325);
PAINT GREEN (-2300 2325);
DISPLAY INVISIBLE (-2300 2325);
FORCEADD GND..1
(-500 2000);
FORCEPROP 3 LASTPIN (-500 2050) SIG_NAME GND\g
J 0
(-490 2060);
DISPLAY 0.659574 (-490 2060);
PAINT MONO (-490 2060);
DISPLAY INVISIBLE (-490 2060);
FORCEPROP 1 LAST SIZE 1B
J 0
(-425 1950);
DISPLAY 0.851064 (-425 1950);
PAINT GREEN (-425 1950);
DISPLAY INVISIBLE (-425 1950);
FORCEPROP 2 LAST CDS_LIB mstr_symbols
J 0
(-500 2000);
DISPLAY 0.723404 (-500 2000);
DISPLAY INVISIBLE (-500 2000);
FORCEPROP 1 LAST BODY_TYPE PLUMBING
J 0
(-545 1957);
DISPLAY 0.340426 (-545 1957);
PAINT GREEN (-545 1957);
DISPLAY INVISIBLE (-545 1957);
FORCEPROP 1 LAST PATH I152
J 0
(-425 2000);
DISPLAY 0.872340 (-425 2000);
PAINT GREEN (-425 2000);
DISPLAY INVISIBLE (-425 2000);
FORCEPROP 1 LAST VOLTAGE 0.0
J 0
(-545 1957);
DISPLAY 0.723404 (-545 1957);
PAINT SKYBLUE (-545 1957);
DISPLAY INVISIBLE (-545 1957);
FORCEPROP 1 LAST HDL_POWER GND
J 0
(-500 2150);
DISPLAY 0.851064 (-500 2150);
PAINT GREEN (-500 2150);
DISPLAY INVISIBLE (-500 2150);
FORCEADD OFFPAGE..5
(-8575 2125);
FORCEPROP 2 LAST $XR0 14 
J 0
(-8799 2125);
DISPLAY 0.638298 (-8799 2125);
PAINT MONO (-8799 2125);
FORCEPROP 2 LAST PATH I167
J 0
(-8525 2200);
DISPLAY 0.808511 (-8525 2200);
DISPLAY INVISIBLE (-8525 2200);
FORCEPROP 1 LAST COMMENT_BODY TRUE
J 0
(-8475 2050);
DISPLAY 0.872340 (-8475 2050);
PAINT GREEN (-8475 2050);
DISPLAY INVISIBLE (-8475 2050);
FORCEPROP 1 LAST OFFPAGE TRUE
J 0
(-8250 2000);
DISPLAY 0.872340 (-8250 2000);
PAINT GREEN (-8250 2000);
DISPLAY INVISIBLE (-8250 2000);
FORCEPROP 2 LAST CDS_LIB mstr_standard
J 0
(-8575 2125);
DISPLAY 0.808511 (-8575 2125);
DISPLAY INVISIBLE (-8575 2125);
FORCEADD OFFPAGE..5
(-8575 2175);
FORCEPROP 2 LAST $XR0 14 
J 0
(-8799 2175);
DISPLAY 0.638298 (-8799 2175);
PAINT MONO (-8799 2175);
FORCEPROP 2 LAST PATH I168
J 0
(-8525 2250);
DISPLAY 0.808511 (-8525 2250);
DISPLAY INVISIBLE (-8525 2250);
FORCEPROP 1 LAST COMMENT_BODY TRUE
J 0
(-8475 2100);
DISPLAY 0.872340 (-8475 2100);
PAINT GREEN (-8475 2100);
DISPLAY INVISIBLE (-8475 2100);
FORCEPROP 1 LAST OFFPAGE TRUE
J 0
(-8250 2050);
DISPLAY 0.872340 (-8250 2050);
PAINT GREEN (-8250 2050);
DISPLAY INVISIBLE (-8250 2050);
FORCEPROP 2 LAST CDS_LIB mstr_standard
J 0
(-8575 2175);
DISPLAY 0.808511 (-8575 2175);
DISPLAY INVISIBLE (-8575 2175);
FORCEADD OFFPAGE..6
(-8575 3775);
FORCEPROP 2 LAST $XR0 14 
J 0
(-8854 3775);
DISPLAY 0.638298 (-8854 3775);
PAINT MONO (-8854 3775);
FORCEPROP 2 LAST PATH I174
J 0
(-8525 3850);
DISPLAY 0.808511 (-8525 3850);
DISPLAY INVISIBLE (-8525 3850);
FORCEPROP 1 LAST COMMENT_BODY TRUE
J 0
(-8475 3700);
DISPLAY 0.872340 (-8475 3700);
PAINT GREEN (-8475 3700);
DISPLAY INVISIBLE (-8475 3700);
FORCEPROP 1 LAST OFFPAGE TRUE
J 0
(-8250 3650);
DISPLAY 0.872340 (-8250 3650);
PAINT GREEN (-8250 3650);
DISPLAY INVISIBLE (-8250 3650);
FORCEPROP 2 LAST CDS_LIB mstr_standard
J 0
(-8575 3775);
DISPLAY 0.723404 (-8575 3775);
PAINT MONO (-8575 3775);
DISPLAY INVISIBLE (-8575 3775);
FORCEADD OFFPAGE..1
(-8425 3275);
FORCEPROP 2 LAST $XR0 14 
J 0
(-8646 3275);
DISPLAY 0.638298 (-8646 3275);
PAINT MONO (-8646 3275);
FORCEPROP 2 LAST PATH I176
J 0
(-8625 3500);
DISPLAY 0.808511 (-8625 3500);
DISPLAY INVISIBLE (-8625 3500);
FORCEPROP 1 LAST COMMENT_BODY TRUE
J 0
(-8300 3175);
DISPLAY 0.872340 (-8300 3175);
PAINT GREEN (-8300 3175);
DISPLAY INVISIBLE (-8300 3175);
FORCEPROP 1 LAST OFFPAGE TRUE
J 0
(-8100 3150);
DISPLAY 0.872340 (-8100 3150);
PAINT GREEN (-8100 3150);
DISPLAY INVISIBLE (-8100 3150);
FORCEPROP 2 LAST CDS_LIB mstr_standard
J 0
(-8425 3275);
DISPLAY 0.808511 (-8425 3275);
DISPLAY INVISIBLE (-8425 3275);
FORCEADD VCC_CORE..1
(-8775 3650);
FORCEPROP 3 LASTPIN (-8775 3600) SIG_NAME P3V3_STBY\g
J 0
(-8765 3610);
DISPLAY 0.659574 (-8765 3610);
PAINT MONO (-8765 3610);
DISPLAY INVISIBLE (-8765 3610);
FORCEPROP 1 LAST HDL_POWER P3V3_STBY
J 1
(-8775 3700);
DISPLAY 0.489362 (-8775 3700);
PAINT GREEN (-8775 3700);
FORCEPROP 2 LAST CDS_LIB mstr_symbols
J 0
(-8775 3650);
PAINT MONO (-8775 3650);
DISPLAY INVISIBLE (-8775 3650);
FORCEPROP 1 LAST PATH I177
J 0
(-8725 3675);
DISPLAY 0.872340 (-8725 3675);
PAINT GREEN (-8725 3675);
DISPLAY INVISIBLE (-8725 3675);
FORCEPROP 0 LAST VOLTAGE 3.3
J 0
(-9050 3800);
DISPLAY 1.021277 (-9050 3800);
PAINT SKYBLUE (-9050 3800);
DISPLAY INVISIBLE (-9050 3800);
FORCEPROP 2 LAST ROOM PVCCINFAON_CPU0_CTRL
J 0
(-8775 3750);
DISPLAY 0.808511 (-8775 3750);
PAINT RED (-8775 3750);
DISPLAY INVISIBLE (-8775 3750);
FORCEADD OFFPAGE..1
(-8575 4275);
FORCEPROP 2 LAST $XR0 14 
J 0
(-8826 4275);
DISPLAY 0.638298 (-8826 4275);
PAINT MONO (-8826 4275);
FORCEPROP 2 LAST PATH I178
J 0
(-8525 4350);
DISPLAY 0.808511 (-8525 4350);
DISPLAY INVISIBLE (-8525 4350);
FORCEPROP 1 LAST COMMENT_BODY TRUE
J 0
(-8450 4175);
DISPLAY 0.872340 (-8450 4175);
PAINT GREEN (-8450 4175);
DISPLAY INVISIBLE (-8450 4175);
FORCEPROP 1 LAST OFFPAGE TRUE
J 0
(-8250 4150);
DISPLAY 0.872340 (-8250 4150);
PAINT GREEN (-8250 4150);
DISPLAY INVISIBLE (-8250 4150);
FORCEPROP 2 LAST CDS_LIB mstr_standard
J 0
(-8575 4275);
DISPLAY 0.808511 (-8575 4275);
DISPLAY INVISIBLE (-8575 4275);
FORCEADD OFFPAGE..6
(-8575 4225);
FORCEPROP 2 LAST $XR0 14 
J 0
(-8854 4225);
DISPLAY 0.638298 (-8854 4225);
PAINT MONO (-8854 4225);
FORCEPROP 2 LAST PATH I179
J 0
(-8525 4300);
DISPLAY 0.808511 (-8525 4300);
DISPLAY INVISIBLE (-8525 4300);
FORCEPROP 1 LAST COMMENT_BODY TRUE
J 0
(-8475 4150);
DISPLAY 0.872340 (-8475 4150);
PAINT GREEN (-8475 4150);
DISPLAY INVISIBLE (-8475 4150);
FORCEPROP 1 LAST OFFPAGE TRUE
J 0
(-8250 4100);
DISPLAY 0.872340 (-8250 4100);
PAINT GREEN (-8250 4100);
DISPLAY INVISIBLE (-8250 4100);
FORCEPROP 2 LAST CDS_LIB mstr_standard
J 0
(-8575 4225);
DISPLAY 0.723404 (-8575 4225);
PAINT MONO (-8575 4225);
DISPLAY INVISIBLE (-8575 4225);
FORCEADD OFFPAGE..1
(-8575 4325);
FORCEPROP 2 LAST $XR0 14 
J 0
(-8826 4325);
DISPLAY 0.638298 (-8826 4325);
PAINT MONO (-8826 4325);
FORCEPROP 2 LAST PATH I180
J 0
(-8525 4400);
DISPLAY 0.808511 (-8525 4400);
DISPLAY INVISIBLE (-8525 4400);
FORCEPROP 1 LAST COMMENT_BODY TRUE
J 0
(-8450 4225);
DISPLAY 0.872340 (-8450 4225);
PAINT GREEN (-8450 4225);
DISPLAY INVISIBLE (-8450 4225);
FORCEPROP 1 LAST OFFPAGE TRUE
J 0
(-8250 4200);
DISPLAY 0.872340 (-8250 4200);
PAINT GREEN (-8250 4200);
DISPLAY INVISIBLE (-8250 4200);
FORCEPROP 2 LAST CDS_LIB mstr_standard
J 0
(-8575 4325);
DISPLAY 0.723404 (-8575 4325);
PAINT MONO (-8575 4325);
DISPLAY INVISIBLE (-8575 4325);
FORCEADD OFFPAGE..1
(-8575 4425);
FORCEPROP 2 LAST $XR0 14 
J 0
(-8826 4425);
DISPLAY 0.638298 (-8826 4425);
PAINT MONO (-8826 4425);
FORCEPROP 2 LAST PATH I181
J 0
(-8525 4500);
DISPLAY 0.808511 (-8525 4500);
DISPLAY INVISIBLE (-8525 4500);
FORCEPROP 1 LAST COMMENT_BODY TRUE
J 0
(-8450 4325);
DISPLAY 0.872340 (-8450 4325);
PAINT GREEN (-8450 4325);
DISPLAY INVISIBLE (-8450 4325);
FORCEPROP 1 LAST OFFPAGE TRUE
J 0
(-8250 4300);
DISPLAY 0.872340 (-8250 4300);
PAINT GREEN (-8250 4300);
DISPLAY INVISIBLE (-8250 4300);
FORCEPROP 2 LAST CDS_LIB mstr_standard
J 0
(-8575 4425);
DISPLAY 0.808511 (-8575 4425);
DISPLAY INVISIBLE (-8575 4425);
FORCEADD OFFPAGE..1
(-8575 4475);
FORCEPROP 2 LAST $XR0 14 
J 0
(-8826 4475);
DISPLAY 0.638298 (-8826 4475);
PAINT MONO (-8826 4475);
FORCEPROP 2 LAST PATH I182
J 0
(-8525 4550);
DISPLAY 0.808511 (-8525 4550);
DISPLAY INVISIBLE (-8525 4550);
FORCEPROP 1 LAST COMMENT_BODY TRUE
J 0
(-8450 4375);
DISPLAY 0.872340 (-8450 4375);
PAINT GREEN (-8450 4375);
DISPLAY INVISIBLE (-8450 4375);
FORCEPROP 1 LAST OFFPAGE TRUE
J 0
(-8250 4350);
DISPLAY 0.872340 (-8250 4350);
PAINT GREEN (-8250 4350);
DISPLAY INVISIBLE (-8250 4350);
FORCEPROP 2 LAST CDS_LIB mstr_standard
J 0
(-8575 4475);
DISPLAY 0.723404 (-8575 4475);
PAINT MONO (-8575 4475);
DISPLAY INVISIBLE (-8575 4475);
FORCEADD OFFPAGE..1
(-8575 4575);
FORCEPROP 2 LAST $XR0 14 
J 0
(-8826 4575);
DISPLAY 0.638298 (-8826 4575);
PAINT MONO (-8826 4575);
FORCEPROP 2 LAST PATH I183
J 0
(-8525 4650);
DISPLAY 0.808511 (-8525 4650);
DISPLAY INVISIBLE (-8525 4650);
FORCEPROP 1 LAST COMMENT_BODY TRUE
J 0
(-8450 4475);
DISPLAY 0.872340 (-8450 4475);
PAINT GREEN (-8450 4475);
DISPLAY INVISIBLE (-8450 4475);
FORCEPROP 1 LAST OFFPAGE TRUE
J 0
(-8250 4450);
DISPLAY 0.872340 (-8250 4450);
PAINT GREEN (-8250 4450);
DISPLAY INVISIBLE (-8250 4450);
FORCEPROP 2 LAST CDS_LIB mstr_standard
J 0
(-8575 4575);
DISPLAY 0.808511 (-8575 4575);
DISPLAY INVISIBLE (-8575 4575);
FORCEADD OFFPAGE..1
(-8575 4625);
FORCEPROP 2 LAST $XR0 14 
J 0
(-8826 4625);
DISPLAY 0.638298 (-8826 4625);
PAINT MONO (-8826 4625);
FORCEPROP 2 LAST PATH I184
J 0
(-8525 4700);
DISPLAY 0.808511 (-8525 4700);
DISPLAY INVISIBLE (-8525 4700);
FORCEPROP 1 LAST COMMENT_BODY TRUE
J 0
(-8450 4525);
DISPLAY 0.872340 (-8450 4525);
PAINT GREEN (-8450 4525);
DISPLAY INVISIBLE (-8450 4525);
FORCEPROP 1 LAST OFFPAGE TRUE
J 0
(-8250 4500);
DISPLAY 0.872340 (-8250 4500);
PAINT GREEN (-8250 4500);
DISPLAY INVISIBLE (-8250 4500);
FORCEPROP 2 LAST CDS_LIB mstr_standard
J 0
(-8575 4625);
DISPLAY 0.723404 (-8575 4625);
PAINT MONO (-8575 4625);
DISPLAY INVISIBLE (-8575 4625);
FORCEADD OFFPAGE..1
(-8575 4775);
FORCEPROP 2 LAST $XR0 14 
J 0
(-8826 4775);
DISPLAY 0.638298 (-8826 4775);
PAINT MONO (-8826 4775);
FORCEPROP 2 LAST PATH I185
J 0
(-8525 4850);
DISPLAY 0.808511 (-8525 4850);
DISPLAY INVISIBLE (-8525 4850);
FORCEPROP 1 LAST COMMENT_BODY TRUE
J 0
(-8450 4675);
DISPLAY 0.872340 (-8450 4675);
PAINT GREEN (-8450 4675);
DISPLAY INVISIBLE (-8450 4675);
FORCEPROP 1 LAST OFFPAGE TRUE
J 0
(-8250 4650);
DISPLAY 0.872340 (-8250 4650);
PAINT GREEN (-8250 4650);
DISPLAY INVISIBLE (-8250 4650);
FORCEPROP 2 LAST CDS_LIB mstr_standard
J 0
(-8575 4775);
DISPLAY 0.723404 (-8575 4775);
PAINT MONO (-8575 4775);
DISPLAY INVISIBLE (-8575 4775);
FORCEADD OFFPAGE..1
(-8575 4725);
FORCEPROP 2 LAST $XR0 14 
J 0
(-8826 4725);
DISPLAY 0.638298 (-8826 4725);
PAINT MONO (-8826 4725);
FORCEPROP 2 LAST PATH I186
J 0
(-8525 4800);
DISPLAY 0.808511 (-8525 4800);
DISPLAY INVISIBLE (-8525 4800);
FORCEPROP 1 LAST COMMENT_BODY TRUE
J 0
(-8450 4625);
DISPLAY 0.872340 (-8450 4625);
PAINT GREEN (-8450 4625);
DISPLAY INVISIBLE (-8450 4625);
FORCEPROP 1 LAST OFFPAGE TRUE
J 0
(-8250 4600);
DISPLAY 0.872340 (-8250 4600);
PAINT GREEN (-8250 4600);
DISPLAY INVISIBLE (-8250 4600);
FORCEPROP 2 LAST CDS_LIB mstr_standard
J 0
(-8575 4725);
DISPLAY 0.808511 (-8575 4725);
DISPLAY INVISIBLE (-8575 4725);
FORCEADD TAP..1
R 2
(-7975 3425);
FORCEPROP 3 LASTPIN (-7925 3425) SIG_NAME M_E_CPU0_SB_CB<1>
J 0
(-7915 3435);
DISPLAY 0.659574 (-7915 3435);
PAINT MONO (-7915 3435);
DISPLAY INVISIBLE (-7915 3435);
FORCEPROP 1 LASTPIN (-7925 3425) BN 1
J 2
(-7913 3433);
DISPLAY 0.489362 (-7913 3433);
PAINT GREEN (-7913 3433);
FORCEPROP 2 LAST CDS_LIB mstr_standard
J 0
(-7975 3425);
DISPLAY 0.723404 (-7975 3425);
PAINT MONO (-7975 3425);
DISPLAY INVISIBLE (-7975 3425);
FORCEPROP 1 LAST BODY_TYPE PLUMBING
J 2
(-7975 3475);
DISPLAY 0.872340 (-7975 3475);
PAINT GREEN (-7975 3475);
DISPLAY INVISIBLE (-7975 3475);
FORCEPROP 1 LAST HDL_TAP TRUE
J 2
(-8300 3300);
DISPLAY 0.872340 (-8300 3300);
DISPLAY INVISIBLE (-8300 3300);
FORCEPROP 1 LAST PATH I187
J 2
(-7973 3425);
DISPLAY 0.872340 (-7973 3425);
PAINT GREEN (-7973 3425);
DISPLAY INVISIBLE (-7973 3425);
FORCEADD TAP..1
R 2
(-7975 3475);
FORCEPROP 3 LASTPIN (-7925 3475) SIG_NAME M_E_CPU0_SB_CB<2>
J 0
(-7915 3485);
DISPLAY 0.659574 (-7915 3485);
PAINT MONO (-7915 3485);
DISPLAY INVISIBLE (-7915 3485);
FORCEPROP 1 LASTPIN (-7925 3475) BN 2
J 2
(-7913 3483);
DISPLAY 0.489362 (-7913 3483);
PAINT GREEN (-7913 3483);
FORCEPROP 2 LAST CDS_LIB mstr_standard
J 0
(-7975 3475);
DISPLAY 0.723404 (-7975 3475);
PAINT MONO (-7975 3475);
DISPLAY INVISIBLE (-7975 3475);
FORCEPROP 1 LAST BODY_TYPE PLUMBING
J 2
(-7975 3525);
DISPLAY 0.872340 (-7975 3525);
PAINT GREEN (-7975 3525);
DISPLAY INVISIBLE (-7975 3525);
FORCEPROP 1 LAST HDL_TAP TRUE
J 2
(-8300 3350);
DISPLAY 0.872340 (-8300 3350);
DISPLAY INVISIBLE (-8300 3350);
FORCEPROP 1 LAST PATH I188
J 2
(-7973 3475);
DISPLAY 0.872340 (-7973 3475);
PAINT GREEN (-7973 3475);
DISPLAY INVISIBLE (-7973 3475);
FORCEADD TAP..1
R 2
(-7975 3375);
FORCEPROP 3 LASTPIN (-7925 3375) SIG_NAME M_E_CPU0_SB_CB<0>
J 0
(-7915 3385);
DISPLAY 0.659574 (-7915 3385);
PAINT MONO (-7915 3385);
DISPLAY INVISIBLE (-7915 3385);
FORCEPROP 1 LASTPIN (-7925 3375) BN 0
J 2
(-7913 3383);
DISPLAY 0.489362 (-7913 3383);
PAINT GREEN (-7913 3383);
FORCEPROP 2 LAST CDS_LIB mstr_standard
J 0
(-7975 3375);
DISPLAY 0.723404 (-7975 3375);
PAINT MONO (-7975 3375);
DISPLAY INVISIBLE (-7975 3375);
FORCEPROP 1 LAST BODY_TYPE PLUMBING
J 2
(-7975 3425);
DISPLAY 0.872340 (-7975 3425);
PAINT GREEN (-7975 3425);
DISPLAY INVISIBLE (-7975 3425);
FORCEPROP 1 LAST HDL_TAP TRUE
J 2
(-8300 3250);
DISPLAY 0.872340 (-8300 3250);
DISPLAY INVISIBLE (-8300 3250);
FORCEPROP 1 LAST PATH I189
J 2
(-7973 3375);
DISPLAY 0.872340 (-7973 3375);
PAINT GREEN (-7973 3375);
DISPLAY INVISIBLE (-7973 3375);
FORCEADD TAP..1
R 2
(-7975 3525);
FORCEPROP 3 LASTPIN (-7925 3525) SIG_NAME M_E_CPU0_SB_CB<3>
J 0
(-7915 3535);
DISPLAY 0.659574 (-7915 3535);
PAINT MONO (-7915 3535);
DISPLAY INVISIBLE (-7915 3535);
FORCEPROP 1 LASTPIN (-7925 3525) BN 3
J 2
(-7913 3533);
DISPLAY 0.489362 (-7913 3533);
PAINT GREEN (-7913 3533);
FORCEPROP 2 LAST CDS_LIB mstr_standard
J 0
(-7975 3525);
DISPLAY 0.723404 (-7975 3525);
PAINT MONO (-7975 3525);
DISPLAY INVISIBLE (-7975 3525);
FORCEPROP 1 LAST BODY_TYPE PLUMBING
J 2
(-7975 3575);
DISPLAY 0.872340 (-7975 3575);
PAINT GREEN (-7975 3575);
DISPLAY INVISIBLE (-7975 3575);
FORCEPROP 1 LAST HDL_TAP TRUE
J 2
(-8300 3400);
DISPLAY 0.872340 (-8300 3400);
DISPLAY INVISIBLE (-8300 3400);
FORCEPROP 1 LAST PATH I190
J 2
(-7973 3525);
DISPLAY 0.872340 (-7973 3525);
PAINT GREEN (-7973 3525);
DISPLAY INVISIBLE (-7973 3525);
FORCEADD TAP..1
R 2
(-7975 3575);
FORCEPROP 3 LASTPIN (-7925 3575) SIG_NAME M_E_CPU0_SB_CB<4>
J 0
(-7915 3585);
DISPLAY 0.659574 (-7915 3585);
PAINT MONO (-7915 3585);
DISPLAY INVISIBLE (-7915 3585);
FORCEPROP 1 LASTPIN (-7925 3575) BN 4
J 2
(-7913 3583);
DISPLAY 0.489362 (-7913 3583);
PAINT GREEN (-7913 3583);
FORCEPROP 2 LAST CDS_LIB mstr_standard
J 0
(-7975 3575);
DISPLAY 0.723404 (-7975 3575);
PAINT MONO (-7975 3575);
DISPLAY INVISIBLE (-7975 3575);
FORCEPROP 1 LAST BODY_TYPE PLUMBING
J 2
(-7975 3625);
DISPLAY 0.872340 (-7975 3625);
PAINT GREEN (-7975 3625);
DISPLAY INVISIBLE (-7975 3625);
FORCEPROP 1 LAST HDL_TAP TRUE
J 2
(-8300 3450);
DISPLAY 0.872340 (-8300 3450);
DISPLAY INVISIBLE (-8300 3450);
FORCEPROP 1 LAST PATH I191
J 2
(-7973 3575);
DISPLAY 0.872340 (-7973 3575);
PAINT GREEN (-7973 3575);
DISPLAY INVISIBLE (-7973 3575);
FORCEADD TAP..1
R 2
(-7975 3625);
FORCEPROP 3 LASTPIN (-7925 3625) SIG_NAME M_E_CPU0_SB_CB<5>
J 0
(-7915 3635);
DISPLAY 0.659574 (-7915 3635);
PAINT MONO (-7915 3635);
DISPLAY INVISIBLE (-7915 3635);
FORCEPROP 1 LASTPIN (-7925 3625) BN 5
J 2
(-7913 3633);
DISPLAY 0.489362 (-7913 3633);
PAINT GREEN (-7913 3633);
FORCEPROP 2 LAST CDS_LIB mstr_standard
J 0
(-7975 3625);
DISPLAY 0.723404 (-7975 3625);
PAINT MONO (-7975 3625);
DISPLAY INVISIBLE (-7975 3625);
FORCEPROP 1 LAST BODY_TYPE PLUMBING
J 2
(-7975 3675);
DISPLAY 0.872340 (-7975 3675);
PAINT GREEN (-7975 3675);
DISPLAY INVISIBLE (-7975 3675);
FORCEPROP 1 LAST HDL_TAP TRUE
J 2
(-8300 3500);
DISPLAY 0.872340 (-8300 3500);
DISPLAY INVISIBLE (-8300 3500);
FORCEPROP 1 LAST PATH I192
J 2
(-7973 3625);
DISPLAY 0.872340 (-7973 3625);
PAINT GREEN (-7973 3625);
DISPLAY INVISIBLE (-7973 3625);
FORCEADD TAP..1
R 2
(-7975 3725);
FORCEPROP 3 LASTPIN (-7925 3725) SIG_NAME M_E_CPU0_SB_CB<7>
J 0
(-7915 3735);
DISPLAY 0.659574 (-7915 3735);
PAINT MONO (-7915 3735);
DISPLAY INVISIBLE (-7915 3735);
FORCEPROP 1 LASTPIN (-7925 3725) BN 7
J 2
(-7913 3733);
DISPLAY 0.489362 (-7913 3733);
PAINT GREEN (-7913 3733);
FORCEPROP 2 LAST CDS_LIB mstr_standard
J 0
(-7975 3725);
DISPLAY 0.723404 (-7975 3725);
PAINT MONO (-7975 3725);
DISPLAY INVISIBLE (-7975 3725);
FORCEPROP 1 LAST BODY_TYPE PLUMBING
J 2
(-7975 3775);
DISPLAY 0.872340 (-7975 3775);
PAINT GREEN (-7975 3775);
DISPLAY INVISIBLE (-7975 3775);
FORCEPROP 1 LAST HDL_TAP TRUE
J 2
(-8300 3600);
DISPLAY 0.872340 (-8300 3600);
DISPLAY INVISIBLE (-8300 3600);
FORCEPROP 1 LAST PATH I193
J 2
(-7973 3725);
DISPLAY 0.872340 (-7973 3725);
PAINT GREEN (-7973 3725);
DISPLAY INVISIBLE (-7973 3725);
FORCEADD TAP..1
R 2
(-7975 3675);
FORCEPROP 3 LASTPIN (-7925 3675) SIG_NAME M_E_CPU0_SB_CB<6>
J 0
(-7915 3685);
DISPLAY 0.659574 (-7915 3685);
PAINT MONO (-7915 3685);
DISPLAY INVISIBLE (-7915 3685);
FORCEPROP 1 LASTPIN (-7925 3675) BN 6
J 2
(-7913 3683);
DISPLAY 0.489362 (-7913 3683);
PAINT GREEN (-7913 3683);
FORCEPROP 2 LAST CDS_LIB mstr_standard
J 0
(-7975 3675);
DISPLAY 0.723404 (-7975 3675);
PAINT MONO (-7975 3675);
DISPLAY INVISIBLE (-7975 3675);
FORCEPROP 1 LAST BODY_TYPE PLUMBING
J 2
(-7975 3725);
DISPLAY 0.872340 (-7975 3725);
PAINT GREEN (-7975 3725);
DISPLAY INVISIBLE (-7975 3725);
FORCEPROP 1 LAST HDL_TAP TRUE
J 2
(-8300 3550);
DISPLAY 0.872340 (-8300 3550);
DISPLAY INVISIBLE (-8300 3550);
FORCEPROP 1 LAST PATH I194
J 2
(-7973 3675);
DISPLAY 0.872340 (-7973 3675);
PAINT GREEN (-7973 3675);
DISPLAY INVISIBLE (-7973 3675);
FORCEADD TAP..1
R 2
(-7975 3925);
FORCEPROP 3 LASTPIN (-7925 3925) SIG_NAME M_E_CPU0_SA_CB<2>
J 0
(-7915 3935);
DISPLAY 0.659574 (-7915 3935);
PAINT MONO (-7915 3935);
DISPLAY INVISIBLE (-7915 3935);
FORCEPROP 1 LASTPIN (-7925 3925) BN 2
J 2
(-7913 3933);
DISPLAY 0.489362 (-7913 3933);
PAINT GREEN (-7913 3933);
FORCEPROP 2 LAST CDS_LIB mstr_standard
J 0
(-7975 3925);
DISPLAY 0.723404 (-7975 3925);
PAINT MONO (-7975 3925);
DISPLAY INVISIBLE (-7975 3925);
FORCEPROP 1 LAST BODY_TYPE PLUMBING
J 2
(-7975 3975);
DISPLAY 0.872340 (-7975 3975);
PAINT GREEN (-7975 3975);
DISPLAY INVISIBLE (-7975 3975);
FORCEPROP 1 LAST HDL_TAP TRUE
J 2
(-8300 3800);
DISPLAY 0.872340 (-8300 3800);
DISPLAY INVISIBLE (-8300 3800);
FORCEPROP 1 LAST PATH I195
J 2
(-7973 3925);
DISPLAY 0.872340 (-7973 3925);
PAINT GREEN (-7973 3925);
DISPLAY INVISIBLE (-7973 3925);
FORCEADD TAP..1
R 2
(-7975 3875);
FORCEPROP 3 LASTPIN (-7925 3875) SIG_NAME M_E_CPU0_SA_CB<1>
J 0
(-7915 3885);
DISPLAY 0.659574 (-7915 3885);
PAINT MONO (-7915 3885);
DISPLAY INVISIBLE (-7915 3885);
FORCEPROP 1 LASTPIN (-7925 3875) BN 1
J 2
(-7913 3883);
DISPLAY 0.489362 (-7913 3883);
PAINT GREEN (-7913 3883);
FORCEPROP 2 LAST CDS_LIB mstr_standard
J 0
(-7975 3875);
DISPLAY 0.723404 (-7975 3875);
PAINT MONO (-7975 3875);
DISPLAY INVISIBLE (-7975 3875);
FORCEPROP 1 LAST BODY_TYPE PLUMBING
J 2
(-7975 3925);
DISPLAY 0.872340 (-7975 3925);
PAINT GREEN (-7975 3925);
DISPLAY INVISIBLE (-7975 3925);
FORCEPROP 1 LAST HDL_TAP TRUE
J 2
(-8300 3750);
DISPLAY 0.872340 (-8300 3750);
DISPLAY INVISIBLE (-8300 3750);
FORCEPROP 1 LAST PATH I196
J 2
(-7973 3875);
DISPLAY 0.872340 (-7973 3875);
PAINT GREEN (-7973 3875);
DISPLAY INVISIBLE (-7973 3875);
FORCEADD TAP..1
R 2
(-7975 3825);
FORCEPROP 3 LASTPIN (-7925 3825) SIG_NAME M_E_CPU0_SA_CB<0>
J 0
(-7915 3835);
DISPLAY 0.659574 (-7915 3835);
PAINT MONO (-7915 3835);
DISPLAY INVISIBLE (-7915 3835);
FORCEPROP 1 LASTPIN (-7925 3825) BN 0
J 2
(-7913 3833);
DISPLAY 0.489362 (-7913 3833);
PAINT GREEN (-7913 3833);
FORCEPROP 2 LAST CDS_LIB mstr_standard
J 0
(-7975 3825);
DISPLAY 0.723404 (-7975 3825);
PAINT MONO (-7975 3825);
DISPLAY INVISIBLE (-7975 3825);
FORCEPROP 1 LAST BODY_TYPE PLUMBING
J 2
(-7975 3875);
DISPLAY 0.872340 (-7975 3875);
PAINT GREEN (-7975 3875);
DISPLAY INVISIBLE (-7975 3875);
FORCEPROP 1 LAST HDL_TAP TRUE
J 2
(-8300 3700);
DISPLAY 0.872340 (-8300 3700);
DISPLAY INVISIBLE (-8300 3700);
FORCEPROP 1 LAST PATH I197
J 2
(-7973 3825);
DISPLAY 0.872340 (-7973 3825);
PAINT GREEN (-7973 3825);
DISPLAY INVISIBLE (-7973 3825);
FORCEADD TAP..1
R 2
(-7975 3975);
FORCEPROP 3 LASTPIN (-7925 3975) SIG_NAME M_E_CPU0_SA_CB<3>
J 0
(-7915 3985);
DISPLAY 0.659574 (-7915 3985);
PAINT MONO (-7915 3985);
DISPLAY INVISIBLE (-7915 3985);
FORCEPROP 1 LASTPIN (-7925 3975) BN 3
J 2
(-7913 3983);
DISPLAY 0.489362 (-7913 3983);
PAINT GREEN (-7913 3983);
FORCEPROP 2 LAST CDS_LIB mstr_standard
J 0
(-7975 3975);
DISPLAY 0.723404 (-7975 3975);
PAINT MONO (-7975 3975);
DISPLAY INVISIBLE (-7975 3975);
FORCEPROP 1 LAST BODY_TYPE PLUMBING
J 2
(-7975 4025);
DISPLAY 0.872340 (-7975 4025);
PAINT GREEN (-7975 4025);
DISPLAY INVISIBLE (-7975 4025);
FORCEPROP 1 LAST HDL_TAP TRUE
J 2
(-8300 3850);
DISPLAY 0.872340 (-8300 3850);
DISPLAY INVISIBLE (-8300 3850);
FORCEPROP 1 LAST PATH I198
J 2
(-7973 3975);
DISPLAY 0.872340 (-7973 3975);
PAINT GREEN (-7973 3975);
DISPLAY INVISIBLE (-7973 3975);
FORCEADD TAP..1
R 2
(-7975 4025);
FORCEPROP 3 LASTPIN (-7925 4025) SIG_NAME M_E_CPU0_SA_CB<4>
J 0
(-7915 4035);
DISPLAY 0.659574 (-7915 4035);
PAINT MONO (-7915 4035);
DISPLAY INVISIBLE (-7915 4035);
FORCEPROP 1 LASTPIN (-7925 4025) BN 4
J 2
(-7913 4033);
DISPLAY 0.489362 (-7913 4033);
PAINT GREEN (-7913 4033);
FORCEPROP 2 LAST CDS_LIB mstr_standard
J 0
(-7975 4025);
DISPLAY 0.723404 (-7975 4025);
PAINT MONO (-7975 4025);
DISPLAY INVISIBLE (-7975 4025);
FORCEPROP 1 LAST BODY_TYPE PLUMBING
J 2
(-7975 4075);
DISPLAY 0.872340 (-7975 4075);
PAINT GREEN (-7975 4075);
DISPLAY INVISIBLE (-7975 4075);
FORCEPROP 1 LAST HDL_TAP TRUE
J 2
(-8300 3900);
DISPLAY 0.872340 (-8300 3900);
DISPLAY INVISIBLE (-8300 3900);
FORCEPROP 1 LAST PATH I199
J 2
(-7973 4025);
DISPLAY 0.872340 (-7973 4025);
PAINT GREEN (-7973 4025);
DISPLAY INVISIBLE (-7973 4025);
FORCEADD TAP..1
R 2
(-7975 4075);
FORCEPROP 3 LASTPIN (-7925 4075) SIG_NAME M_E_CPU0_SA_CB<5>
J 0
(-7915 4085);
DISPLAY 0.659574 (-7915 4085);
PAINT MONO (-7915 4085);
DISPLAY INVISIBLE (-7915 4085);
FORCEPROP 1 LASTPIN (-7925 4075) BN 5
J 2
(-7913 4083);
DISPLAY 0.489362 (-7913 4083);
PAINT GREEN (-7913 4083);
FORCEPROP 2 LAST CDS_LIB mstr_standard
J 0
(-7975 4075);
DISPLAY 0.723404 (-7975 4075);
PAINT MONO (-7975 4075);
DISPLAY INVISIBLE (-7975 4075);
FORCEPROP 1 LAST BODY_TYPE PLUMBING
J 2
(-7975 4125);
DISPLAY 0.872340 (-7975 4125);
PAINT GREEN (-7975 4125);
DISPLAY INVISIBLE (-7975 4125);
FORCEPROP 1 LAST HDL_TAP TRUE
J 2
(-8300 3950);
DISPLAY 0.872340 (-8300 3950);
DISPLAY INVISIBLE (-8300 3950);
FORCEPROP 1 LAST PATH I200
J 2
(-7973 4075);
DISPLAY 0.872340 (-7973 4075);
PAINT GREEN (-7973 4075);
DISPLAY INVISIBLE (-7973 4075);
FORCEADD TAP..1
R 2
(-7975 4125);
FORCEPROP 3 LASTPIN (-7925 4125) SIG_NAME M_E_CPU0_SA_CB<6>
J 0
(-7915 4135);
DISPLAY 0.659574 (-7915 4135);
PAINT MONO (-7915 4135);
DISPLAY INVISIBLE (-7915 4135);
FORCEPROP 1 LASTPIN (-7925 4125) BN 6
J 2
(-7913 4133);
DISPLAY 0.489362 (-7913 4133);
PAINT GREEN (-7913 4133);
FORCEPROP 2 LAST CDS_LIB mstr_standard
J 0
(-7975 4125);
DISPLAY 0.723404 (-7975 4125);
PAINT MONO (-7975 4125);
DISPLAY INVISIBLE (-7975 4125);
FORCEPROP 1 LAST BODY_TYPE PLUMBING
J 2
(-7975 4175);
DISPLAY 0.872340 (-7975 4175);
PAINT GREEN (-7975 4175);
DISPLAY INVISIBLE (-7975 4175);
FORCEPROP 1 LAST HDL_TAP TRUE
J 2
(-8300 4000);
DISPLAY 0.872340 (-8300 4000);
DISPLAY INVISIBLE (-8300 4000);
FORCEPROP 1 LAST PATH I201
J 2
(-7973 4125);
DISPLAY 0.872340 (-7973 4125);
PAINT GREEN (-7973 4125);
DISPLAY INVISIBLE (-7973 4125);
FORCEADD TAP..1
R 2
(-7975 4175);
FORCEPROP 3 LASTPIN (-7925 4175) SIG_NAME M_E_CPU0_SA_CB<7>
J 0
(-7915 4185);
DISPLAY 0.659574 (-7915 4185);
PAINT MONO (-7915 4185);
DISPLAY INVISIBLE (-7915 4185);
FORCEPROP 1 LASTPIN (-7925 4175) BN 7
J 2
(-7913 4183);
DISPLAY 0.489362 (-7913 4183);
PAINT GREEN (-7913 4183);
FORCEPROP 2 LAST CDS_LIB mstr_standard
J 0
(-7975 4175);
DISPLAY 0.723404 (-7975 4175);
PAINT MONO (-7975 4175);
DISPLAY INVISIBLE (-7975 4175);
FORCEPROP 1 LAST BODY_TYPE PLUMBING
J 2
(-7975 4225);
DISPLAY 0.872340 (-7975 4225);
PAINT GREEN (-7975 4225);
DISPLAY INVISIBLE (-7975 4225);
FORCEPROP 1 LAST HDL_TAP TRUE
J 2
(-8300 4050);
DISPLAY 0.872340 (-8300 4050);
DISPLAY INVISIBLE (-8300 4050);
FORCEPROP 1 LAST PATH I202
J 2
(-7973 4175);
DISPLAY 0.872340 (-7973 4175);
PAINT GREEN (-7973 4175);
DISPLAY INVISIBLE (-7973 4175);
FORCEADD TAP..1
R 2
(-7975 5025);
FORCEPROP 3 LASTPIN (-7925 5025) SIG_NAME M_E_CPU0_SB_CA<3>
J 0
(-7915 5035);
DISPLAY 0.659574 (-7915 5035);
PAINT MONO (-7915 5035);
DISPLAY INVISIBLE (-7915 5035);
FORCEPROP 1 LASTPIN (-7925 5025) BN 3
J 2
(-7913 5033);
DISPLAY 0.489362 (-7913 5033);
PAINT GREEN (-7913 5033);
FORCEPROP 2 LAST CDS_LIB mstr_standard
J 0
(-7975 5025);
DISPLAY 0.723404 (-7975 5025);
PAINT MONO (-7975 5025);
DISPLAY INVISIBLE (-7975 5025);
FORCEPROP 1 LAST BODY_TYPE PLUMBING
J 2
(-7975 5075);
DISPLAY 0.872340 (-7975 5075);
PAINT GREEN (-7975 5075);
DISPLAY INVISIBLE (-7975 5075);
FORCEPROP 1 LAST HDL_TAP TRUE
J 2
(-8300 4900);
DISPLAY 0.872340 (-8300 4900);
DISPLAY INVISIBLE (-8300 4900);
FORCEPROP 1 LAST PATH I203
J 2
(-7973 5025);
DISPLAY 0.872340 (-7973 5025);
PAINT GREEN (-7973 5025);
DISPLAY INVISIBLE (-7973 5025);
FORCEADD TAP..1
R 2
(-7975 4925);
FORCEPROP 3 LASTPIN (-7925 4925) SIG_NAME M_E_CPU0_SB_CA<1>
J 0
(-7915 4935);
DISPLAY 0.659574 (-7915 4935);
PAINT MONO (-7915 4935);
DISPLAY INVISIBLE (-7915 4935);
FORCEPROP 1 LASTPIN (-7925 4925) BN 1
J 2
(-7913 4933);
DISPLAY 0.489362 (-7913 4933);
PAINT GREEN (-7913 4933);
FORCEPROP 2 LAST CDS_LIB mstr_standard
J 0
(-7975 4925);
DISPLAY 0.723404 (-7975 4925);
PAINT MONO (-7975 4925);
DISPLAY INVISIBLE (-7975 4925);
FORCEPROP 1 LAST BODY_TYPE PLUMBING
J 2
(-7975 4975);
DISPLAY 0.872340 (-7975 4975);
PAINT GREEN (-7975 4975);
DISPLAY INVISIBLE (-7975 4975);
FORCEPROP 1 LAST HDL_TAP TRUE
J 2
(-8300 4800);
DISPLAY 0.872340 (-8300 4800);
DISPLAY INVISIBLE (-8300 4800);
FORCEPROP 1 LAST PATH I204
J 2
(-7973 4925);
DISPLAY 0.872340 (-7973 4925);
PAINT GREEN (-7973 4925);
DISPLAY INVISIBLE (-7973 4925);
FORCEADD TAP..1
R 2
(-7975 4875);
FORCEPROP 3 LASTPIN (-7925 4875) SIG_NAME M_E_CPU0_SB_CA<0>
J 0
(-7915 4885);
DISPLAY 0.659574 (-7915 4885);
PAINT MONO (-7915 4885);
DISPLAY INVISIBLE (-7915 4885);
FORCEPROP 1 LASTPIN (-7925 4875) BN 0
J 2
(-7913 4883);
DISPLAY 0.489362 (-7913 4883);
PAINT GREEN (-7913 4883);
FORCEPROP 2 LAST CDS_LIB mstr_standard
J 0
(-7975 4875);
DISPLAY 0.723404 (-7975 4875);
PAINT MONO (-7975 4875);
DISPLAY INVISIBLE (-7975 4875);
FORCEPROP 1 LAST BODY_TYPE PLUMBING
J 2
(-7975 4925);
DISPLAY 0.872340 (-7975 4925);
PAINT GREEN (-7975 4925);
DISPLAY INVISIBLE (-7975 4925);
FORCEPROP 1 LAST HDL_TAP TRUE
J 2
(-8300 4750);
DISPLAY 0.872340 (-8300 4750);
DISPLAY INVISIBLE (-8300 4750);
FORCEPROP 1 LAST PATH I205
J 2
(-7973 4875);
DISPLAY 0.872340 (-7973 4875);
PAINT GREEN (-7973 4875);
DISPLAY INVISIBLE (-7973 4875);
FORCEADD TAP..1
R 2
(-7975 4975);
FORCEPROP 3 LASTPIN (-7925 4975) SIG_NAME M_E_CPU0_SB_CA<2>
J 0
(-7915 4985);
DISPLAY 0.659574 (-7915 4985);
PAINT MONO (-7915 4985);
DISPLAY INVISIBLE (-7915 4985);
FORCEPROP 1 LASTPIN (-7925 4975) BN 2
J 2
(-7913 4983);
DISPLAY 0.489362 (-7913 4983);
PAINT GREEN (-7913 4983);
FORCEPROP 2 LAST CDS_LIB mstr_standard
J 0
(-7975 4975);
DISPLAY 0.723404 (-7975 4975);
PAINT MONO (-7975 4975);
DISPLAY INVISIBLE (-7975 4975);
FORCEPROP 1 LAST BODY_TYPE PLUMBING
J 2
(-7975 5025);
DISPLAY 0.872340 (-7975 5025);
PAINT GREEN (-7975 5025);
DISPLAY INVISIBLE (-7975 5025);
FORCEPROP 1 LAST HDL_TAP TRUE
J 2
(-8300 4850);
DISPLAY 0.872340 (-8300 4850);
DISPLAY INVISIBLE (-8300 4850);
FORCEPROP 1 LAST PATH I206
J 2
(-7973 4975);
DISPLAY 0.872340 (-7973 4975);
PAINT GREEN (-7973 4975);
DISPLAY INVISIBLE (-7973 4975);
FORCEADD TAP..1
(-6275 2425);
FORCEPROP 3 LASTPIN (-6325 2425) SIG_NAME M_E_CPU0_SB_DQ<1>
J 0
(-6315 2435);
DISPLAY 0.659574 (-6315 2435);
PAINT MONO (-6315 2435);
DISPLAY INVISIBLE (-6315 2435);
FORCEPROP 1 LASTPIN (-6325 2425) BN 1
J 0
(-6337 2433);
DISPLAY 0.489362 (-6337 2433);
PAINT GREEN (-6337 2433);
FORCEPROP 2 LAST CDS_LIB mstr_standard
J 0
(-6275 2425);
DISPLAY 0.723404 (-6275 2425);
PAINT MONO (-6275 2425);
DISPLAY INVISIBLE (-6275 2425);
FORCEPROP 1 LAST BODY_TYPE PLUMBING
J 0
(-6275 2475);
DISPLAY 0.872340 (-6275 2475);
PAINT GREEN (-6275 2475);
DISPLAY INVISIBLE (-6275 2475);
FORCEPROP 1 LAST HDL_TAP TRUE
J 0
(-5950 2300);
DISPLAY 0.872340 (-5950 2300);
DISPLAY INVISIBLE (-5950 2300);
FORCEPROP 1 LAST PATH I207
J 0
(-6277 2425);
DISPLAY 0.872340 (-6277 2425);
PAINT GREEN (-6277 2425);
DISPLAY INVISIBLE (-6277 2425);
FORCEADD TAP..1
(-6275 2375);
FORCEPROP 3 LASTPIN (-6325 2375) SIG_NAME M_E_CPU0_SB_DQ<0>
J 0
(-6315 2385);
DISPLAY 0.659574 (-6315 2385);
PAINT MONO (-6315 2385);
DISPLAY INVISIBLE (-6315 2385);
FORCEPROP 1 LASTPIN (-6325 2375) BN 0
J 0
(-6337 2383);
DISPLAY 0.489362 (-6337 2383);
PAINT GREEN (-6337 2383);
FORCEPROP 2 LAST CDS_LIB mstr_standard
J 0
(-6275 2375);
DISPLAY 0.723404 (-6275 2375);
PAINT MONO (-6275 2375);
DISPLAY INVISIBLE (-6275 2375);
FORCEPROP 1 LAST BODY_TYPE PLUMBING
J 0
(-6275 2425);
DISPLAY 0.872340 (-6275 2425);
PAINT GREEN (-6275 2425);
DISPLAY INVISIBLE (-6275 2425);
FORCEPROP 1 LAST HDL_TAP TRUE
J 0
(-5950 2250);
DISPLAY 0.872340 (-5950 2250);
DISPLAY INVISIBLE (-5950 2250);
FORCEPROP 1 LAST PATH I208
J 0
(-6277 2375);
DISPLAY 0.872340 (-6277 2375);
PAINT GREEN (-6277 2375);
DISPLAY INVISIBLE (-6277 2375);
FORCEADD TAP..1
(-6275 2475);
FORCEPROP 3 LASTPIN (-6325 2475) SIG_NAME M_E_CPU0_SB_DQ<2>
J 0
(-6315 2485);
DISPLAY 0.659574 (-6315 2485);
PAINT MONO (-6315 2485);
DISPLAY INVISIBLE (-6315 2485);
FORCEPROP 1 LASTPIN (-6325 2475) BN 2
J 0
(-6337 2483);
DISPLAY 0.489362 (-6337 2483);
PAINT GREEN (-6337 2483);
FORCEPROP 2 LAST CDS_LIB mstr_standard
J 0
(-6275 2475);
DISPLAY 0.723404 (-6275 2475);
PAINT MONO (-6275 2475);
DISPLAY INVISIBLE (-6275 2475);
FORCEPROP 1 LAST BODY_TYPE PLUMBING
J 0
(-6275 2525);
DISPLAY 0.872340 (-6275 2525);
PAINT GREEN (-6275 2525);
DISPLAY INVISIBLE (-6275 2525);
FORCEPROP 1 LAST HDL_TAP TRUE
J 0
(-5950 2350);
DISPLAY 0.872340 (-5950 2350);
DISPLAY INVISIBLE (-5950 2350);
FORCEPROP 1 LAST PATH I209
J 0
(-6277 2475);
DISPLAY 0.872340 (-6277 2475);
PAINT GREEN (-6277 2475);
DISPLAY INVISIBLE (-6277 2475);
FORCEADD TAP..1
(-6275 2525);
FORCEPROP 3 LASTPIN (-6325 2525) SIG_NAME M_E_CPU0_SB_DQ<3>
J 0
(-6315 2535);
DISPLAY 0.659574 (-6315 2535);
PAINT MONO (-6315 2535);
DISPLAY INVISIBLE (-6315 2535);
FORCEPROP 1 LASTPIN (-6325 2525) BN 3
J 0
(-6337 2533);
DISPLAY 0.489362 (-6337 2533);
PAINT GREEN (-6337 2533);
FORCEPROP 2 LAST CDS_LIB mstr_standard
J 0
(-6275 2525);
DISPLAY 0.723404 (-6275 2525);
PAINT MONO (-6275 2525);
DISPLAY INVISIBLE (-6275 2525);
FORCEPROP 1 LAST BODY_TYPE PLUMBING
J 0
(-6275 2575);
DISPLAY 0.872340 (-6275 2575);
PAINT GREEN (-6275 2575);
DISPLAY INVISIBLE (-6275 2575);
FORCEPROP 1 LAST HDL_TAP TRUE
J 0
(-5950 2400);
DISPLAY 0.872340 (-5950 2400);
DISPLAY INVISIBLE (-5950 2400);
FORCEPROP 1 LAST PATH I210
J 0
(-6277 2525);
DISPLAY 0.872340 (-6277 2525);
PAINT GREEN (-6277 2525);
DISPLAY INVISIBLE (-6277 2525);
FORCEADD TAP..1
(-6275 2575);
FORCEPROP 3 LASTPIN (-6325 2575) SIG_NAME M_E_CPU0_SB_DQ<4>
J 0
(-6315 2585);
DISPLAY 0.659574 (-6315 2585);
PAINT MONO (-6315 2585);
DISPLAY INVISIBLE (-6315 2585);
FORCEPROP 1 LASTPIN (-6325 2575) BN 4
J 0
(-6337 2583);
DISPLAY 0.489362 (-6337 2583);
PAINT GREEN (-6337 2583);
FORCEPROP 2 LAST CDS_LIB mstr_standard
J 0
(-6275 2575);
DISPLAY 0.723404 (-6275 2575);
PAINT MONO (-6275 2575);
DISPLAY INVISIBLE (-6275 2575);
FORCEPROP 1 LAST BODY_TYPE PLUMBING
J 0
(-6275 2625);
DISPLAY 0.872340 (-6275 2625);
PAINT GREEN (-6275 2625);
DISPLAY INVISIBLE (-6275 2625);
FORCEPROP 1 LAST HDL_TAP TRUE
J 0
(-5950 2450);
DISPLAY 0.872340 (-5950 2450);
DISPLAY INVISIBLE (-5950 2450);
FORCEPROP 1 LAST PATH I211
J 0
(-6277 2575);
DISPLAY 0.872340 (-6277 2575);
PAINT GREEN (-6277 2575);
DISPLAY INVISIBLE (-6277 2575);
FORCEADD TAP..1
(-6275 2625);
FORCEPROP 3 LASTPIN (-6325 2625) SIG_NAME M_E_CPU0_SB_DQ<5>
J 0
(-6315 2635);
DISPLAY 0.659574 (-6315 2635);
PAINT MONO (-6315 2635);
DISPLAY INVISIBLE (-6315 2635);
FORCEPROP 1 LASTPIN (-6325 2625) BN 5
J 0
(-6337 2633);
DISPLAY 0.489362 (-6337 2633);
PAINT GREEN (-6337 2633);
FORCEPROP 2 LAST CDS_LIB mstr_standard
J 0
(-6275 2625);
DISPLAY 0.723404 (-6275 2625);
PAINT MONO (-6275 2625);
DISPLAY INVISIBLE (-6275 2625);
FORCEPROP 1 LAST BODY_TYPE PLUMBING
J 0
(-6275 2675);
DISPLAY 0.872340 (-6275 2675);
PAINT GREEN (-6275 2675);
DISPLAY INVISIBLE (-6275 2675);
FORCEPROP 1 LAST HDL_TAP TRUE
J 0
(-5950 2500);
DISPLAY 0.872340 (-5950 2500);
DISPLAY INVISIBLE (-5950 2500);
FORCEPROP 1 LAST PATH I212
J 0
(-6277 2625);
DISPLAY 0.872340 (-6277 2625);
PAINT GREEN (-6277 2625);
DISPLAY INVISIBLE (-6277 2625);
FORCEADD TAP..1
(-6275 2725);
FORCEPROP 3 LASTPIN (-6325 2725) SIG_NAME M_E_CPU0_SB_DQ<7>
J 0
(-6315 2735);
DISPLAY 0.659574 (-6315 2735);
PAINT MONO (-6315 2735);
DISPLAY INVISIBLE (-6315 2735);
FORCEPROP 1 LASTPIN (-6325 2725) BN 7
J 0
(-6337 2733);
DISPLAY 0.489362 (-6337 2733);
PAINT GREEN (-6337 2733);
FORCEPROP 2 LAST CDS_LIB mstr_standard
J 0
(-6275 2725);
DISPLAY 0.723404 (-6275 2725);
PAINT MONO (-6275 2725);
DISPLAY INVISIBLE (-6275 2725);
FORCEPROP 1 LAST BODY_TYPE PLUMBING
J 0
(-6275 2775);
DISPLAY 0.872340 (-6275 2775);
PAINT GREEN (-6275 2775);
DISPLAY INVISIBLE (-6275 2775);
FORCEPROP 1 LAST HDL_TAP TRUE
J 0
(-5950 2600);
DISPLAY 0.872340 (-5950 2600);
DISPLAY INVISIBLE (-5950 2600);
FORCEPROP 1 LAST PATH I213
J 0
(-6277 2725);
DISPLAY 0.872340 (-6277 2725);
PAINT GREEN (-6277 2725);
DISPLAY INVISIBLE (-6277 2725);
FORCEADD TAP..1
(-6275 2675);
FORCEPROP 3 LASTPIN (-6325 2675) SIG_NAME M_E_CPU0_SB_DQ<6>
J 0
(-6315 2685);
DISPLAY 0.659574 (-6315 2685);
PAINT MONO (-6315 2685);
DISPLAY INVISIBLE (-6315 2685);
FORCEPROP 1 LASTPIN (-6325 2675) BN 6
J 0
(-6337 2683);
DISPLAY 0.489362 (-6337 2683);
PAINT GREEN (-6337 2683);
FORCEPROP 2 LAST CDS_LIB mstr_standard
J 0
(-6275 2675);
DISPLAY 0.723404 (-6275 2675);
PAINT MONO (-6275 2675);
DISPLAY INVISIBLE (-6275 2675);
FORCEPROP 1 LAST BODY_TYPE PLUMBING
J 0
(-6275 2725);
DISPLAY 0.872340 (-6275 2725);
PAINT GREEN (-6275 2725);
DISPLAY INVISIBLE (-6275 2725);
FORCEPROP 1 LAST HDL_TAP TRUE
J 0
(-5950 2550);
DISPLAY 0.872340 (-5950 2550);
DISPLAY INVISIBLE (-5950 2550);
FORCEPROP 1 LAST PATH I214
J 0
(-6277 2675);
DISPLAY 0.872340 (-6277 2675);
PAINT GREEN (-6277 2675);
DISPLAY INVISIBLE (-6277 2675);
FORCEADD TAP..1
(-6275 2775);
FORCEPROP 3 LASTPIN (-6325 2775) SIG_NAME M_E_CPU0_SB_DQ<8>
J 0
(-6315 2785);
DISPLAY 0.659574 (-6315 2785);
PAINT MONO (-6315 2785);
DISPLAY INVISIBLE (-6315 2785);
FORCEPROP 1 LASTPIN (-6325 2775) BN 8
J 0
(-6337 2783);
DISPLAY 0.489362 (-6337 2783);
PAINT GREEN (-6337 2783);
FORCEPROP 2 LAST CDS_LIB mstr_standard
J 0
(-6275 2775);
DISPLAY 0.723404 (-6275 2775);
PAINT MONO (-6275 2775);
DISPLAY INVISIBLE (-6275 2775);
FORCEPROP 1 LAST BODY_TYPE PLUMBING
J 0
(-6275 2825);
DISPLAY 0.872340 (-6275 2825);
PAINT GREEN (-6275 2825);
DISPLAY INVISIBLE (-6275 2825);
FORCEPROP 1 LAST HDL_TAP TRUE
J 0
(-5950 2650);
DISPLAY 0.872340 (-5950 2650);
DISPLAY INVISIBLE (-5950 2650);
FORCEPROP 1 LAST PATH I215
J 0
(-6277 2775);
DISPLAY 0.872340 (-6277 2775);
PAINT GREEN (-6277 2775);
DISPLAY INVISIBLE (-6277 2775);
FORCEADD TAP..1
(-6275 2825);
FORCEPROP 3 LASTPIN (-6325 2825) SIG_NAME M_E_CPU0_SB_DQ<9>
J 0
(-6315 2835);
DISPLAY 0.659574 (-6315 2835);
PAINT MONO (-6315 2835);
DISPLAY INVISIBLE (-6315 2835);
FORCEPROP 1 LASTPIN (-6325 2825) BN 9
J 0
(-6337 2833);
DISPLAY 0.489362 (-6337 2833);
PAINT GREEN (-6337 2833);
FORCEPROP 2 LAST CDS_LIB mstr_standard
J 0
(-6275 2825);
DISPLAY 0.723404 (-6275 2825);
PAINT MONO (-6275 2825);
DISPLAY INVISIBLE (-6275 2825);
FORCEPROP 1 LAST BODY_TYPE PLUMBING
J 0
(-6275 2875);
DISPLAY 0.872340 (-6275 2875);
PAINT GREEN (-6275 2875);
DISPLAY INVISIBLE (-6275 2875);
FORCEPROP 1 LAST HDL_TAP TRUE
J 0
(-5950 2700);
DISPLAY 0.872340 (-5950 2700);
DISPLAY INVISIBLE (-5950 2700);
FORCEPROP 1 LAST PATH I216
J 0
(-6277 2825);
DISPLAY 0.872340 (-6277 2825);
PAINT GREEN (-6277 2825);
DISPLAY INVISIBLE (-6277 2825);
FORCEADD TAP..1
(-6275 2875);
FORCEPROP 3 LASTPIN (-6325 2875) SIG_NAME M_E_CPU0_SB_DQ<10>
J 0
(-6315 2885);
DISPLAY 0.659574 (-6315 2885);
PAINT MONO (-6315 2885);
DISPLAY INVISIBLE (-6315 2885);
FORCEPROP 1 LASTPIN (-6325 2875) BN 10
J 0
(-6337 2883);
DISPLAY 0.489362 (-6337 2883);
PAINT GREEN (-6337 2883);
FORCEPROP 2 LAST CDS_LIB mstr_standard
J 0
(-6275 2875);
DISPLAY 0.723404 (-6275 2875);
PAINT MONO (-6275 2875);
DISPLAY INVISIBLE (-6275 2875);
FORCEPROP 1 LAST BODY_TYPE PLUMBING
J 0
(-6275 2925);
DISPLAY 0.872340 (-6275 2925);
PAINT GREEN (-6275 2925);
DISPLAY INVISIBLE (-6275 2925);
FORCEPROP 1 LAST HDL_TAP TRUE
J 0
(-5950 2750);
DISPLAY 0.872340 (-5950 2750);
DISPLAY INVISIBLE (-5950 2750);
FORCEPROP 1 LAST PATH I217
J 0
(-6277 2875);
DISPLAY 0.872340 (-6277 2875);
PAINT GREEN (-6277 2875);
DISPLAY INVISIBLE (-6277 2875);
FORCEADD TAP..1
(-6275 2925);
FORCEPROP 3 LASTPIN (-6325 2925) SIG_NAME M_E_CPU0_SB_DQ<11>
J 0
(-6315 2935);
DISPLAY 0.659574 (-6315 2935);
PAINT MONO (-6315 2935);
DISPLAY INVISIBLE (-6315 2935);
FORCEPROP 1 LASTPIN (-6325 2925) BN 11
J 0
(-6337 2933);
DISPLAY 0.489362 (-6337 2933);
PAINT GREEN (-6337 2933);
FORCEPROP 2 LAST CDS_LIB mstr_standard
J 0
(-6275 2925);
DISPLAY 0.723404 (-6275 2925);
PAINT MONO (-6275 2925);
DISPLAY INVISIBLE (-6275 2925);
FORCEPROP 1 LAST BODY_TYPE PLUMBING
J 0
(-6275 2975);
DISPLAY 0.872340 (-6275 2975);
PAINT GREEN (-6275 2975);
DISPLAY INVISIBLE (-6275 2975);
FORCEPROP 1 LAST HDL_TAP TRUE
J 0
(-5950 2800);
DISPLAY 0.872340 (-5950 2800);
DISPLAY INVISIBLE (-5950 2800);
FORCEPROP 1 LAST PATH I218
J 0
(-6277 2925);
DISPLAY 0.872340 (-6277 2925);
PAINT GREEN (-6277 2925);
DISPLAY INVISIBLE (-6277 2925);
FORCEADD TAP..1
(-6275 2975);
FORCEPROP 3 LASTPIN (-6325 2975) SIG_NAME M_E_CPU0_SB_DQ<12>
J 0
(-6315 2985);
DISPLAY 0.659574 (-6315 2985);
PAINT MONO (-6315 2985);
DISPLAY INVISIBLE (-6315 2985);
FORCEPROP 1 LASTPIN (-6325 2975) BN 12
J 0
(-6337 2983);
DISPLAY 0.489362 (-6337 2983);
PAINT GREEN (-6337 2983);
FORCEPROP 2 LAST CDS_LIB mstr_standard
J 0
(-6275 2975);
DISPLAY 0.723404 (-6275 2975);
PAINT MONO (-6275 2975);
DISPLAY INVISIBLE (-6275 2975);
FORCEPROP 1 LAST BODY_TYPE PLUMBING
J 0
(-6275 3025);
DISPLAY 0.872340 (-6275 3025);
PAINT GREEN (-6275 3025);
DISPLAY INVISIBLE (-6275 3025);
FORCEPROP 1 LAST HDL_TAP TRUE
J 0
(-5950 2850);
DISPLAY 0.872340 (-5950 2850);
DISPLAY INVISIBLE (-5950 2850);
FORCEPROP 1 LAST PATH I219
J 0
(-6277 2975);
DISPLAY 0.872340 (-6277 2975);
PAINT GREEN (-6277 2975);
DISPLAY INVISIBLE (-6277 2975);
FORCEADD TAP..1
(-6275 3025);
FORCEPROP 3 LASTPIN (-6325 3025) SIG_NAME M_E_CPU0_SB_DQ<13>
J 0
(-6315 3035);
DISPLAY 0.659574 (-6315 3035);
PAINT MONO (-6315 3035);
DISPLAY INVISIBLE (-6315 3035);
FORCEPROP 1 LASTPIN (-6325 3025) BN 13
J 0
(-6337 3033);
DISPLAY 0.489362 (-6337 3033);
PAINT GREEN (-6337 3033);
FORCEPROP 2 LAST CDS_LIB mstr_standard
J 0
(-6275 3025);
DISPLAY 0.723404 (-6275 3025);
PAINT MONO (-6275 3025);
DISPLAY INVISIBLE (-6275 3025);
FORCEPROP 1 LAST BODY_TYPE PLUMBING
J 0
(-6275 3075);
DISPLAY 0.872340 (-6275 3075);
PAINT GREEN (-6275 3075);
DISPLAY INVISIBLE (-6275 3075);
FORCEPROP 1 LAST HDL_TAP TRUE
J 0
(-5950 2900);
DISPLAY 0.872340 (-5950 2900);
DISPLAY INVISIBLE (-5950 2900);
FORCEPROP 1 LAST PATH I220
J 0
(-6277 3025);
DISPLAY 0.872340 (-6277 3025);
PAINT GREEN (-6277 3025);
DISPLAY INVISIBLE (-6277 3025);
FORCEADD TAP..1
(-6275 3125);
FORCEPROP 3 LASTPIN (-6325 3125) SIG_NAME M_E_CPU0_SB_DQ<15>
J 0
(-6315 3135);
DISPLAY 0.659574 (-6315 3135);
PAINT MONO (-6315 3135);
DISPLAY INVISIBLE (-6315 3135);
FORCEPROP 1 LASTPIN (-6325 3125) BN 15
J 0
(-6337 3133);
DISPLAY 0.489362 (-6337 3133);
PAINT GREEN (-6337 3133);
FORCEPROP 2 LAST CDS_LIB mstr_standard
J 0
(-6275 3125);
DISPLAY 0.723404 (-6275 3125);
PAINT MONO (-6275 3125);
DISPLAY INVISIBLE (-6275 3125);
FORCEPROP 1 LAST BODY_TYPE PLUMBING
J 0
(-6275 3175);
DISPLAY 0.872340 (-6275 3175);
PAINT GREEN (-6275 3175);
DISPLAY INVISIBLE (-6275 3175);
FORCEPROP 1 LAST HDL_TAP TRUE
J 0
(-5950 3000);
DISPLAY 0.872340 (-5950 3000);
DISPLAY INVISIBLE (-5950 3000);
FORCEPROP 1 LAST PATH I221
J 0
(-6277 3125);
DISPLAY 0.872340 (-6277 3125);
PAINT GREEN (-6277 3125);
DISPLAY INVISIBLE (-6277 3125);
FORCEADD TAP..1
(-6275 3075);
FORCEPROP 3 LASTPIN (-6325 3075) SIG_NAME M_E_CPU0_SB_DQ<14>
J 0
(-6315 3085);
DISPLAY 0.659574 (-6315 3085);
PAINT MONO (-6315 3085);
DISPLAY INVISIBLE (-6315 3085);
FORCEPROP 1 LASTPIN (-6325 3075) BN 14
J 0
(-6337 3083);
DISPLAY 0.489362 (-6337 3083);
PAINT GREEN (-6337 3083);
FORCEPROP 2 LAST CDS_LIB mstr_standard
J 0
(-6275 3075);
DISPLAY 0.723404 (-6275 3075);
PAINT MONO (-6275 3075);
DISPLAY INVISIBLE (-6275 3075);
FORCEPROP 1 LAST BODY_TYPE PLUMBING
J 0
(-6275 3125);
DISPLAY 0.872340 (-6275 3125);
PAINT GREEN (-6275 3125);
DISPLAY INVISIBLE (-6275 3125);
FORCEPROP 1 LAST HDL_TAP TRUE
J 0
(-5950 2950);
DISPLAY 0.872340 (-5950 2950);
DISPLAY INVISIBLE (-5950 2950);
FORCEPROP 1 LAST PATH I222
J 0
(-6277 3075);
DISPLAY 0.872340 (-6277 3075);
PAINT GREEN (-6277 3075);
DISPLAY INVISIBLE (-6277 3075);
FORCEADD TAP..1
(-6275 3275);
FORCEPROP 3 LASTPIN (-6325 3275) SIG_NAME M_E_CPU0_SB_DQ<18>
J 0
(-6315 3285);
DISPLAY 0.659574 (-6315 3285);
PAINT MONO (-6315 3285);
DISPLAY INVISIBLE (-6315 3285);
FORCEPROP 1 LASTPIN (-6325 3275) BN 18
J 0
(-6337 3283);
DISPLAY 0.489362 (-6337 3283);
PAINT GREEN (-6337 3283);
FORCEPROP 2 LAST CDS_LIB mstr_standard
J 0
(-6275 3275);
DISPLAY 0.723404 (-6275 3275);
PAINT MONO (-6275 3275);
DISPLAY INVISIBLE (-6275 3275);
FORCEPROP 1 LAST BODY_TYPE PLUMBING
J 0
(-6275 3325);
DISPLAY 0.872340 (-6275 3325);
PAINT GREEN (-6275 3325);
DISPLAY INVISIBLE (-6275 3325);
FORCEPROP 1 LAST HDL_TAP TRUE
J 0
(-5950 3150);
DISPLAY 0.872340 (-5950 3150);
DISPLAY INVISIBLE (-5950 3150);
FORCEPROP 1 LAST PATH I223
J 0
(-6277 3275);
DISPLAY 0.872340 (-6277 3275);
PAINT GREEN (-6277 3275);
DISPLAY INVISIBLE (-6277 3275);
FORCEADD TAP..1
(-6275 3225);
FORCEPROP 3 LASTPIN (-6325 3225) SIG_NAME M_E_CPU0_SB_DQ<17>
J 0
(-6315 3235);
DISPLAY 0.659574 (-6315 3235);
PAINT MONO (-6315 3235);
DISPLAY INVISIBLE (-6315 3235);
FORCEPROP 1 LASTPIN (-6325 3225) BN 17
J 0
(-6337 3233);
DISPLAY 0.489362 (-6337 3233);
PAINT GREEN (-6337 3233);
FORCEPROP 2 LAST CDS_LIB mstr_standard
J 0
(-6275 3225);
DISPLAY 0.723404 (-6275 3225);
PAINT MONO (-6275 3225);
DISPLAY INVISIBLE (-6275 3225);
FORCEPROP 1 LAST BODY_TYPE PLUMBING
J 0
(-6275 3275);
DISPLAY 0.872340 (-6275 3275);
PAINT GREEN (-6275 3275);
DISPLAY INVISIBLE (-6275 3275);
FORCEPROP 1 LAST HDL_TAP TRUE
J 0
(-5950 3100);
DISPLAY 0.872340 (-5950 3100);
DISPLAY INVISIBLE (-5950 3100);
FORCEPROP 1 LAST PATH I224
J 0
(-6277 3225);
DISPLAY 0.872340 (-6277 3225);
PAINT GREEN (-6277 3225);
DISPLAY INVISIBLE (-6277 3225);
FORCEADD TAP..1
(-6275 3175);
FORCEPROP 3 LASTPIN (-6325 3175) SIG_NAME M_E_CPU0_SB_DQ<16>
J 0
(-6315 3185);
DISPLAY 0.659574 (-6315 3185);
PAINT MONO (-6315 3185);
DISPLAY INVISIBLE (-6315 3185);
FORCEPROP 1 LASTPIN (-6325 3175) BN 16
J 0
(-6337 3183);
DISPLAY 0.489362 (-6337 3183);
PAINT GREEN (-6337 3183);
FORCEPROP 2 LAST CDS_LIB mstr_standard
J 0
(-6275 3175);
DISPLAY 0.723404 (-6275 3175);
PAINT MONO (-6275 3175);
DISPLAY INVISIBLE (-6275 3175);
FORCEPROP 1 LAST BODY_TYPE PLUMBING
J 0
(-6275 3225);
DISPLAY 0.872340 (-6275 3225);
PAINT GREEN (-6275 3225);
DISPLAY INVISIBLE (-6275 3225);
FORCEPROP 1 LAST HDL_TAP TRUE
J 0
(-5950 3050);
DISPLAY 0.872340 (-5950 3050);
DISPLAY INVISIBLE (-5950 3050);
FORCEPROP 1 LAST PATH I225
J 0
(-6277 3175);
DISPLAY 0.872340 (-6277 3175);
PAINT GREEN (-6277 3175);
DISPLAY INVISIBLE (-6277 3175);
FORCEADD TAP..1
(-6275 3425);
FORCEPROP 3 LASTPIN (-6325 3425) SIG_NAME M_E_CPU0_SB_DQ<21>
J 0
(-6315 3435);
DISPLAY 0.659574 (-6315 3435);
PAINT MONO (-6315 3435);
DISPLAY INVISIBLE (-6315 3435);
FORCEPROP 1 LASTPIN (-6325 3425) BN 21
J 0
(-6337 3433);
DISPLAY 0.489362 (-6337 3433);
PAINT GREEN (-6337 3433);
FORCEPROP 2 LAST CDS_LIB mstr_standard
J 0
(-6275 3425);
DISPLAY 0.723404 (-6275 3425);
PAINT MONO (-6275 3425);
DISPLAY INVISIBLE (-6275 3425);
FORCEPROP 1 LAST BODY_TYPE PLUMBING
J 0
(-6275 3475);
DISPLAY 0.872340 (-6275 3475);
PAINT GREEN (-6275 3475);
DISPLAY INVISIBLE (-6275 3475);
FORCEPROP 1 LAST HDL_TAP TRUE
J 0
(-5950 3300);
DISPLAY 0.872340 (-5950 3300);
DISPLAY INVISIBLE (-5950 3300);
FORCEPROP 1 LAST PATH I226
J 0
(-6277 3425);
DISPLAY 0.872340 (-6277 3425);
PAINT GREEN (-6277 3425);
DISPLAY INVISIBLE (-6277 3425);
FORCEADD TAP..1
(-6275 3475);
FORCEPROP 3 LASTPIN (-6325 3475) SIG_NAME M_E_CPU0_SB_DQ<22>
J 0
(-6315 3485);
DISPLAY 0.659574 (-6315 3485);
PAINT MONO (-6315 3485);
DISPLAY INVISIBLE (-6315 3485);
FORCEPROP 1 LASTPIN (-6325 3475) BN 22
J 0
(-6337 3483);
DISPLAY 0.489362 (-6337 3483);
PAINT GREEN (-6337 3483);
FORCEPROP 2 LAST CDS_LIB mstr_standard
J 0
(-6275 3475);
DISPLAY 0.723404 (-6275 3475);
PAINT MONO (-6275 3475);
DISPLAY INVISIBLE (-6275 3475);
FORCEPROP 1 LAST BODY_TYPE PLUMBING
J 0
(-6275 3525);
DISPLAY 0.872340 (-6275 3525);
PAINT GREEN (-6275 3525);
DISPLAY INVISIBLE (-6275 3525);
FORCEPROP 1 LAST HDL_TAP TRUE
J 0
(-5950 3350);
DISPLAY 0.872340 (-5950 3350);
DISPLAY INVISIBLE (-5950 3350);
FORCEPROP 1 LAST PATH I227
J 0
(-6277 3475);
DISPLAY 0.872340 (-6277 3475);
PAINT GREEN (-6277 3475);
DISPLAY INVISIBLE (-6277 3475);
FORCEADD TAP..1
(-6275 3375);
FORCEPROP 3 LASTPIN (-6325 3375) SIG_NAME M_E_CPU0_SB_DQ<20>
J 0
(-6315 3385);
DISPLAY 0.659574 (-6315 3385);
PAINT MONO (-6315 3385);
DISPLAY INVISIBLE (-6315 3385);
FORCEPROP 1 LASTPIN (-6325 3375) BN 20
J 0
(-6337 3383);
DISPLAY 0.489362 (-6337 3383);
PAINT GREEN (-6337 3383);
FORCEPROP 2 LAST CDS_LIB mstr_standard
J 0
(-6275 3375);
DISPLAY 0.723404 (-6275 3375);
PAINT MONO (-6275 3375);
DISPLAY INVISIBLE (-6275 3375);
FORCEPROP 1 LAST BODY_TYPE PLUMBING
J 0
(-6275 3425);
DISPLAY 0.872340 (-6275 3425);
PAINT GREEN (-6275 3425);
DISPLAY INVISIBLE (-6275 3425);
FORCEPROP 1 LAST HDL_TAP TRUE
J 0
(-5950 3250);
DISPLAY 0.872340 (-5950 3250);
DISPLAY INVISIBLE (-5950 3250);
FORCEPROP 1 LAST PATH I228
J 0
(-6277 3375);
DISPLAY 0.872340 (-6277 3375);
PAINT GREEN (-6277 3375);
DISPLAY INVISIBLE (-6277 3375);
FORCEADD TAP..1
(-6275 3525);
FORCEPROP 3 LASTPIN (-6325 3525) SIG_NAME M_E_CPU0_SB_DQ<23>
J 0
(-6315 3535);
DISPLAY 0.659574 (-6315 3535);
PAINT MONO (-6315 3535);
DISPLAY INVISIBLE (-6315 3535);
FORCEPROP 1 LASTPIN (-6325 3525) BN 23
J 0
(-6337 3533);
DISPLAY 0.489362 (-6337 3533);
PAINT GREEN (-6337 3533);
FORCEPROP 2 LAST CDS_LIB mstr_standard
J 0
(-6275 3525);
DISPLAY 0.723404 (-6275 3525);
PAINT MONO (-6275 3525);
DISPLAY INVISIBLE (-6275 3525);
FORCEPROP 1 LAST BODY_TYPE PLUMBING
J 0
(-6275 3575);
DISPLAY 0.872340 (-6275 3575);
PAINT GREEN (-6275 3575);
DISPLAY INVISIBLE (-6275 3575);
FORCEPROP 1 LAST HDL_TAP TRUE
J 0
(-5950 3400);
DISPLAY 0.872340 (-5950 3400);
DISPLAY INVISIBLE (-5950 3400);
FORCEPROP 1 LAST PATH I229
J 0
(-6277 3525);
DISPLAY 0.872340 (-6277 3525);
PAINT GREEN (-6277 3525);
DISPLAY INVISIBLE (-6277 3525);
FORCEADD TAP..1
(-6275 3325);
FORCEPROP 3 LASTPIN (-6325 3325) SIG_NAME M_E_CPU0_SB_DQ<19>
J 0
(-6315 3335);
DISPLAY 0.659574 (-6315 3335);
PAINT MONO (-6315 3335);
DISPLAY INVISIBLE (-6315 3335);
FORCEPROP 1 LASTPIN (-6325 3325) BN 19
J 0
(-6337 3333);
DISPLAY 0.489362 (-6337 3333);
PAINT GREEN (-6337 3333);
FORCEPROP 2 LAST CDS_LIB mstr_standard
J 0
(-6275 3325);
DISPLAY 0.723404 (-6275 3325);
PAINT MONO (-6275 3325);
DISPLAY INVISIBLE (-6275 3325);
FORCEPROP 1 LAST BODY_TYPE PLUMBING
J 0
(-6275 3375);
DISPLAY 0.872340 (-6275 3375);
PAINT GREEN (-6275 3375);
DISPLAY INVISIBLE (-6275 3375);
FORCEPROP 1 LAST HDL_TAP TRUE
J 0
(-5950 3200);
DISPLAY 0.872340 (-5950 3200);
DISPLAY INVISIBLE (-5950 3200);
FORCEPROP 1 LAST PATH I230
J 0
(-6277 3325);
DISPLAY 0.872340 (-6277 3325);
PAINT GREEN (-6277 3325);
DISPLAY INVISIBLE (-6277 3325);
FORCEADD TAP..1
(-6275 3675);
FORCEPROP 3 LASTPIN (-6325 3675) SIG_NAME M_E_CPU0_SB_DQ<26>
J 0
(-6315 3685);
DISPLAY 0.659574 (-6315 3685);
PAINT MONO (-6315 3685);
DISPLAY INVISIBLE (-6315 3685);
FORCEPROP 1 LASTPIN (-6325 3675) BN 26
J 0
(-6337 3683);
DISPLAY 0.489362 (-6337 3683);
PAINT GREEN (-6337 3683);
FORCEPROP 2 LAST CDS_LIB mstr_standard
J 0
(-6275 3675);
DISPLAY 0.723404 (-6275 3675);
PAINT MONO (-6275 3675);
DISPLAY INVISIBLE (-6275 3675);
FORCEPROP 1 LAST BODY_TYPE PLUMBING
J 0
(-6275 3725);
DISPLAY 0.872340 (-6275 3725);
PAINT GREEN (-6275 3725);
DISPLAY INVISIBLE (-6275 3725);
FORCEPROP 1 LAST HDL_TAP TRUE
J 0
(-5950 3550);
DISPLAY 0.872340 (-5950 3550);
DISPLAY INVISIBLE (-5950 3550);
FORCEPROP 1 LAST PATH I231
J 0
(-6277 3675);
DISPLAY 0.872340 (-6277 3675);
PAINT GREEN (-6277 3675);
DISPLAY INVISIBLE (-6277 3675);
FORCEADD TAP..1
(-6275 3725);
FORCEPROP 3 LASTPIN (-6325 3725) SIG_NAME M_E_CPU0_SB_DQ<27>
J 0
(-6315 3735);
DISPLAY 0.659574 (-6315 3735);
PAINT MONO (-6315 3735);
DISPLAY INVISIBLE (-6315 3735);
FORCEPROP 1 LASTPIN (-6325 3725) BN 27
J 0
(-6337 3733);
DISPLAY 0.489362 (-6337 3733);
PAINT GREEN (-6337 3733);
FORCEPROP 2 LAST CDS_LIB mstr_standard
J 0
(-6275 3725);
DISPLAY 0.723404 (-6275 3725);
PAINT MONO (-6275 3725);
DISPLAY INVISIBLE (-6275 3725);
FORCEPROP 1 LAST BODY_TYPE PLUMBING
J 0
(-6275 3775);
DISPLAY 0.872340 (-6275 3775);
PAINT GREEN (-6275 3775);
DISPLAY INVISIBLE (-6275 3775);
FORCEPROP 1 LAST HDL_TAP TRUE
J 0
(-5950 3600);
DISPLAY 0.872340 (-5950 3600);
DISPLAY INVISIBLE (-5950 3600);
FORCEPROP 1 LAST PATH I232
J 0
(-6277 3725);
DISPLAY 0.872340 (-6277 3725);
PAINT GREEN (-6277 3725);
DISPLAY INVISIBLE (-6277 3725);
FORCEADD TAP..1
(-6275 3625);
FORCEPROP 3 LASTPIN (-6325 3625) SIG_NAME M_E_CPU0_SB_DQ<25>
J 0
(-6315 3635);
DISPLAY 0.659574 (-6315 3635);
PAINT MONO (-6315 3635);
DISPLAY INVISIBLE (-6315 3635);
FORCEPROP 1 LASTPIN (-6325 3625) BN 25
J 0
(-6337 3633);
DISPLAY 0.489362 (-6337 3633);
PAINT GREEN (-6337 3633);
FORCEPROP 2 LAST CDS_LIB mstr_standard
J 0
(-6275 3625);
DISPLAY 0.723404 (-6275 3625);
PAINT MONO (-6275 3625);
DISPLAY INVISIBLE (-6275 3625);
FORCEPROP 1 LAST BODY_TYPE PLUMBING
J 0
(-6275 3675);
DISPLAY 0.872340 (-6275 3675);
PAINT GREEN (-6275 3675);
DISPLAY INVISIBLE (-6275 3675);
FORCEPROP 1 LAST HDL_TAP TRUE
J 0
(-5950 3500);
DISPLAY 0.872340 (-5950 3500);
DISPLAY INVISIBLE (-5950 3500);
FORCEPROP 1 LAST PATH I233
J 0
(-6277 3625);
DISPLAY 0.872340 (-6277 3625);
PAINT GREEN (-6277 3625);
DISPLAY INVISIBLE (-6277 3625);
FORCEADD TAP..1
(-6275 3775);
FORCEPROP 3 LASTPIN (-6325 3775) SIG_NAME M_E_CPU0_SB_DQ<28>
J 0
(-6315 3785);
DISPLAY 0.659574 (-6315 3785);
PAINT MONO (-6315 3785);
DISPLAY INVISIBLE (-6315 3785);
FORCEPROP 1 LASTPIN (-6325 3775) BN 28
J 0
(-6337 3783);
DISPLAY 0.489362 (-6337 3783);
PAINT GREEN (-6337 3783);
FORCEPROP 2 LAST CDS_LIB mstr_standard
J 0
(-6275 3775);
DISPLAY 0.723404 (-6275 3775);
PAINT MONO (-6275 3775);
DISPLAY INVISIBLE (-6275 3775);
FORCEPROP 1 LAST BODY_TYPE PLUMBING
J 0
(-6275 3825);
DISPLAY 0.872340 (-6275 3825);
PAINT GREEN (-6275 3825);
DISPLAY INVISIBLE (-6275 3825);
FORCEPROP 1 LAST HDL_TAP TRUE
J 0
(-5950 3650);
DISPLAY 0.872340 (-5950 3650);
DISPLAY INVISIBLE (-5950 3650);
FORCEPROP 1 LAST PATH I234
J 0
(-6277 3775);
DISPLAY 0.872340 (-6277 3775);
PAINT GREEN (-6277 3775);
DISPLAY INVISIBLE (-6277 3775);
FORCEADD TAP..1
(-6275 3575);
FORCEPROP 3 LASTPIN (-6325 3575) SIG_NAME M_E_CPU0_SB_DQ<24>
J 0
(-6315 3585);
DISPLAY 0.659574 (-6315 3585);
PAINT MONO (-6315 3585);
DISPLAY INVISIBLE (-6315 3585);
FORCEPROP 1 LASTPIN (-6325 3575) BN 24
J 0
(-6337 3583);
DISPLAY 0.489362 (-6337 3583);
PAINT GREEN (-6337 3583);
FORCEPROP 2 LAST CDS_LIB mstr_standard
J 0
(-6275 3575);
DISPLAY 0.723404 (-6275 3575);
PAINT MONO (-6275 3575);
DISPLAY INVISIBLE (-6275 3575);
FORCEPROP 1 LAST BODY_TYPE PLUMBING
J 0
(-6275 3625);
DISPLAY 0.872340 (-6275 3625);
PAINT GREEN (-6275 3625);
DISPLAY INVISIBLE (-6275 3625);
FORCEPROP 1 LAST HDL_TAP TRUE
J 0
(-5950 3450);
DISPLAY 0.872340 (-5950 3450);
DISPLAY INVISIBLE (-5950 3450);
FORCEPROP 1 LAST PATH I235
J 0
(-6277 3575);
DISPLAY 0.872340 (-6277 3575);
PAINT GREEN (-6277 3575);
DISPLAY INVISIBLE (-6277 3575);
FORCEADD TAP..1
(-6275 4025);
FORCEPROP 3 LASTPIN (-6325 4025) SIG_NAME M_E_CPU0_SA_DQ<0>
J 0
(-6315 4035);
DISPLAY 0.659574 (-6315 4035);
PAINT MONO (-6315 4035);
DISPLAY INVISIBLE (-6315 4035);
FORCEPROP 1 LASTPIN (-6325 4025) BN 0
J 0
(-6337 4033);
DISPLAY 0.489362 (-6337 4033);
PAINT GREEN (-6337 4033);
FORCEPROP 2 LAST CDS_LIB mstr_standard
J 0
(-6275 4025);
DISPLAY 0.723404 (-6275 4025);
PAINT MONO (-6275 4025);
DISPLAY INVISIBLE (-6275 4025);
FORCEPROP 1 LAST BODY_TYPE PLUMBING
J 0
(-6275 4075);
DISPLAY 0.872340 (-6275 4075);
PAINT GREEN (-6275 4075);
DISPLAY INVISIBLE (-6275 4075);
FORCEPROP 1 LAST HDL_TAP TRUE
J 0
(-5950 3900);
DISPLAY 0.872340 (-5950 3900);
DISPLAY INVISIBLE (-5950 3900);
FORCEPROP 1 LAST PATH I236
J 0
(-6277 4025);
DISPLAY 0.872340 (-6277 4025);
PAINT GREEN (-6277 4025);
DISPLAY INVISIBLE (-6277 4025);
FORCEADD TAP..1
(-6275 3875);
FORCEPROP 3 LASTPIN (-6325 3875) SIG_NAME M_E_CPU0_SB_DQ<30>
J 0
(-6315 3885);
DISPLAY 0.659574 (-6315 3885);
PAINT MONO (-6315 3885);
DISPLAY INVISIBLE (-6315 3885);
FORCEPROP 1 LASTPIN (-6325 3875) BN 30
J 0
(-6337 3883);
DISPLAY 0.489362 (-6337 3883);
PAINT GREEN (-6337 3883);
FORCEPROP 2 LAST CDS_LIB mstr_standard
J 0
(-6275 3875);
DISPLAY 0.723404 (-6275 3875);
PAINT MONO (-6275 3875);
DISPLAY INVISIBLE (-6275 3875);
FORCEPROP 1 LAST BODY_TYPE PLUMBING
J 0
(-6275 3925);
DISPLAY 0.872340 (-6275 3925);
PAINT GREEN (-6275 3925);
DISPLAY INVISIBLE (-6275 3925);
FORCEPROP 1 LAST HDL_TAP TRUE
J 0
(-5950 3750);
DISPLAY 0.872340 (-5950 3750);
DISPLAY INVISIBLE (-5950 3750);
FORCEPROP 1 LAST PATH I237
J 0
(-6277 3875);
DISPLAY 0.872340 (-6277 3875);
PAINT GREEN (-6277 3875);
DISPLAY INVISIBLE (-6277 3875);
FORCEADD TAP..1
(-6275 3925);
FORCEPROP 3 LASTPIN (-6325 3925) SIG_NAME M_E_CPU0_SB_DQ<31>
J 0
(-6315 3935);
DISPLAY 0.659574 (-6315 3935);
PAINT MONO (-6315 3935);
DISPLAY INVISIBLE (-6315 3935);
FORCEPROP 1 LASTPIN (-6325 3925) BN 31
J 0
(-6337 3933);
DISPLAY 0.489362 (-6337 3933);
PAINT GREEN (-6337 3933);
FORCEPROP 2 LAST CDS_LIB mstr_standard
J 0
(-6275 3925);
DISPLAY 0.723404 (-6275 3925);
PAINT MONO (-6275 3925);
DISPLAY INVISIBLE (-6275 3925);
FORCEPROP 1 LAST BODY_TYPE PLUMBING
J 0
(-6275 3975);
DISPLAY 0.872340 (-6275 3975);
PAINT GREEN (-6275 3975);
DISPLAY INVISIBLE (-6275 3975);
FORCEPROP 1 LAST HDL_TAP TRUE
J 0
(-5950 3800);
DISPLAY 0.872340 (-5950 3800);
DISPLAY INVISIBLE (-5950 3800);
FORCEPROP 1 LAST PATH I238
J 0
(-6277 3925);
DISPLAY 0.872340 (-6277 3925);
PAINT GREEN (-6277 3925);
DISPLAY INVISIBLE (-6277 3925);
FORCEADD TAP..1
(-6275 3825);
FORCEPROP 3 LASTPIN (-6325 3825) SIG_NAME M_E_CPU0_SB_DQ<29>
J 0
(-6315 3835);
DISPLAY 0.659574 (-6315 3835);
PAINT MONO (-6315 3835);
DISPLAY INVISIBLE (-6315 3835);
FORCEPROP 1 LASTPIN (-6325 3825) BN 29
J 0
(-6337 3833);
DISPLAY 0.489362 (-6337 3833);
PAINT GREEN (-6337 3833);
FORCEPROP 2 LAST CDS_LIB mstr_standard
J 0
(-6275 3825);
DISPLAY 0.723404 (-6275 3825);
PAINT MONO (-6275 3825);
DISPLAY INVISIBLE (-6275 3825);
FORCEPROP 1 LAST BODY_TYPE PLUMBING
J 0
(-6275 3875);
DISPLAY 0.872340 (-6275 3875);
PAINT GREEN (-6275 3875);
DISPLAY INVISIBLE (-6275 3875);
FORCEPROP 1 LAST HDL_TAP TRUE
J 0
(-5950 3700);
DISPLAY 0.872340 (-5950 3700);
DISPLAY INVISIBLE (-5950 3700);
FORCEPROP 1 LAST PATH I239
J 0
(-6277 3825);
DISPLAY 0.872340 (-6277 3825);
PAINT GREEN (-6277 3825);
DISPLAY INVISIBLE (-6277 3825);
FORCEADD TAP..1
(-6275 4125);
FORCEPROP 3 LASTPIN (-6325 4125) SIG_NAME M_E_CPU0_SA_DQ<2>
J 0
(-6315 4135);
DISPLAY 0.659574 (-6315 4135);
PAINT MONO (-6315 4135);
DISPLAY INVISIBLE (-6315 4135);
FORCEPROP 1 LASTPIN (-6325 4125) BN 2
J 0
(-6337 4133);
DISPLAY 0.489362 (-6337 4133);
PAINT GREEN (-6337 4133);
FORCEPROP 2 LAST CDS_LIB mstr_standard
J 0
(-6275 4125);
DISPLAY 0.723404 (-6275 4125);
PAINT MONO (-6275 4125);
DISPLAY INVISIBLE (-6275 4125);
FORCEPROP 1 LAST BODY_TYPE PLUMBING
J 0
(-6275 4175);
DISPLAY 0.872340 (-6275 4175);
PAINT GREEN (-6275 4175);
DISPLAY INVISIBLE (-6275 4175);
FORCEPROP 1 LAST HDL_TAP TRUE
J 0
(-5950 4000);
DISPLAY 0.872340 (-5950 4000);
DISPLAY INVISIBLE (-5950 4000);
FORCEPROP 1 LAST PATH I240
J 0
(-6277 4125);
DISPLAY 0.872340 (-6277 4125);
PAINT GREEN (-6277 4125);
DISPLAY INVISIBLE (-6277 4125);
FORCEADD TAP..1
(-6275 4075);
FORCEPROP 3 LASTPIN (-6325 4075) SIG_NAME M_E_CPU0_SA_DQ<1>
J 0
(-6315 4085);
DISPLAY 0.659574 (-6315 4085);
PAINT MONO (-6315 4085);
DISPLAY INVISIBLE (-6315 4085);
FORCEPROP 1 LASTPIN (-6325 4075) BN 1
J 0
(-6337 4083);
DISPLAY 0.489362 (-6337 4083);
PAINT GREEN (-6337 4083);
FORCEPROP 2 LAST CDS_LIB mstr_standard
J 0
(-6275 4075);
DISPLAY 0.723404 (-6275 4075);
PAINT MONO (-6275 4075);
DISPLAY INVISIBLE (-6275 4075);
FORCEPROP 1 LAST BODY_TYPE PLUMBING
J 0
(-6275 4125);
DISPLAY 0.872340 (-6275 4125);
PAINT GREEN (-6275 4125);
DISPLAY INVISIBLE (-6275 4125);
FORCEPROP 1 LAST HDL_TAP TRUE
J 0
(-5950 3950);
DISPLAY 0.872340 (-5950 3950);
DISPLAY INVISIBLE (-5950 3950);
FORCEPROP 1 LAST PATH I241
J 0
(-6277 4075);
DISPLAY 0.872340 (-6277 4075);
PAINT GREEN (-6277 4075);
DISPLAY INVISIBLE (-6277 4075);
FORCEADD TAP..1
(-6275 4175);
FORCEPROP 3 LASTPIN (-6325 4175) SIG_NAME M_E_CPU0_SA_DQ<3>
J 0
(-6315 4185);
DISPLAY 0.659574 (-6315 4185);
PAINT MONO (-6315 4185);
DISPLAY INVISIBLE (-6315 4185);
FORCEPROP 1 LASTPIN (-6325 4175) BN 3
J 0
(-6337 4183);
DISPLAY 0.489362 (-6337 4183);
PAINT GREEN (-6337 4183);
FORCEPROP 2 LAST CDS_LIB mstr_standard
J 0
(-6275 4175);
DISPLAY 0.723404 (-6275 4175);
PAINT MONO (-6275 4175);
DISPLAY INVISIBLE (-6275 4175);
FORCEPROP 1 LAST BODY_TYPE PLUMBING
J 0
(-6275 4225);
DISPLAY 0.872340 (-6275 4225);
PAINT GREEN (-6275 4225);
DISPLAY INVISIBLE (-6275 4225);
FORCEPROP 1 LAST HDL_TAP TRUE
J 0
(-5950 4050);
DISPLAY 0.872340 (-5950 4050);
DISPLAY INVISIBLE (-5950 4050);
FORCEPROP 1 LAST PATH I242
J 0
(-6277 4175);
DISPLAY 0.872340 (-6277 4175);
PAINT GREEN (-6277 4175);
DISPLAY INVISIBLE (-6277 4175);
FORCEADD TAP..1
(-6275 4225);
FORCEPROP 3 LASTPIN (-6325 4225) SIG_NAME M_E_CPU0_SA_DQ<4>
J 0
(-6315 4235);
DISPLAY 0.659574 (-6315 4235);
PAINT MONO (-6315 4235);
DISPLAY INVISIBLE (-6315 4235);
FORCEPROP 1 LASTPIN (-6325 4225) BN 4
J 0
(-6337 4233);
DISPLAY 0.489362 (-6337 4233);
PAINT GREEN (-6337 4233);
FORCEPROP 2 LAST CDS_LIB mstr_standard
J 0
(-6275 4225);
DISPLAY 0.723404 (-6275 4225);
PAINT MONO (-6275 4225);
DISPLAY INVISIBLE (-6275 4225);
FORCEPROP 1 LAST BODY_TYPE PLUMBING
J 0
(-6275 4275);
DISPLAY 0.872340 (-6275 4275);
PAINT GREEN (-6275 4275);
DISPLAY INVISIBLE (-6275 4275);
FORCEPROP 1 LAST HDL_TAP TRUE
J 0
(-5950 4100);
DISPLAY 0.872340 (-5950 4100);
DISPLAY INVISIBLE (-5950 4100);
FORCEPROP 1 LAST PATH I243
J 0
(-6277 4225);
DISPLAY 0.872340 (-6277 4225);
PAINT GREEN (-6277 4225);
DISPLAY INVISIBLE (-6277 4225);
FORCEADD TAP..1
(-6275 4275);
FORCEPROP 3 LASTPIN (-6325 4275) SIG_NAME M_E_CPU0_SA_DQ<5>
J 0
(-6315 4285);
DISPLAY 0.659574 (-6315 4285);
PAINT MONO (-6315 4285);
DISPLAY INVISIBLE (-6315 4285);
FORCEPROP 1 LASTPIN (-6325 4275) BN 5
J 0
(-6337 4283);
DISPLAY 0.489362 (-6337 4283);
PAINT GREEN (-6337 4283);
FORCEPROP 2 LAST CDS_LIB mstr_standard
J 0
(-6275 4275);
DISPLAY 0.723404 (-6275 4275);
PAINT MONO (-6275 4275);
DISPLAY INVISIBLE (-6275 4275);
FORCEPROP 1 LAST BODY_TYPE PLUMBING
J 0
(-6275 4325);
DISPLAY 0.872340 (-6275 4325);
PAINT GREEN (-6275 4325);
DISPLAY INVISIBLE (-6275 4325);
FORCEPROP 1 LAST HDL_TAP TRUE
J 0
(-5950 4150);
DISPLAY 0.872340 (-5950 4150);
DISPLAY INVISIBLE (-5950 4150);
FORCEPROP 1 LAST PATH I244
J 0
(-6277 4275);
DISPLAY 0.872340 (-6277 4275);
PAINT GREEN (-6277 4275);
DISPLAY INVISIBLE (-6277 4275);
FORCEADD TAP..1
(-6275 4375);
FORCEPROP 3 LASTPIN (-6325 4375) SIG_NAME M_E_CPU0_SA_DQ<7>
J 0
(-6315 4385);
DISPLAY 0.659574 (-6315 4385);
PAINT MONO (-6315 4385);
DISPLAY INVISIBLE (-6315 4385);
FORCEPROP 1 LASTPIN (-6325 4375) BN 7
J 0
(-6337 4383);
DISPLAY 0.489362 (-6337 4383);
PAINT GREEN (-6337 4383);
FORCEPROP 2 LAST CDS_LIB mstr_standard
J 0
(-6275 4375);
DISPLAY 0.723404 (-6275 4375);
PAINT MONO (-6275 4375);
DISPLAY INVISIBLE (-6275 4375);
FORCEPROP 1 LAST BODY_TYPE PLUMBING
J 0
(-6275 4425);
DISPLAY 0.872340 (-6275 4425);
PAINT GREEN (-6275 4425);
DISPLAY INVISIBLE (-6275 4425);
FORCEPROP 1 LAST HDL_TAP TRUE
J 0
(-5950 4250);
DISPLAY 0.872340 (-5950 4250);
DISPLAY INVISIBLE (-5950 4250);
FORCEPROP 1 LAST PATH I245
J 0
(-6277 4375);
DISPLAY 0.872340 (-6277 4375);
PAINT GREEN (-6277 4375);
DISPLAY INVISIBLE (-6277 4375);
FORCEADD TAP..1
(-6275 4325);
FORCEPROP 3 LASTPIN (-6325 4325) SIG_NAME M_E_CPU0_SA_DQ<6>
J 0
(-6315 4335);
DISPLAY 0.659574 (-6315 4335);
PAINT MONO (-6315 4335);
DISPLAY INVISIBLE (-6315 4335);
FORCEPROP 1 LASTPIN (-6325 4325) BN 6
J 0
(-6337 4333);
DISPLAY 0.489362 (-6337 4333);
PAINT GREEN (-6337 4333);
FORCEPROP 2 LAST CDS_LIB mstr_standard
J 0
(-6275 4325);
DISPLAY 0.723404 (-6275 4325);
PAINT MONO (-6275 4325);
DISPLAY INVISIBLE (-6275 4325);
FORCEPROP 1 LAST BODY_TYPE PLUMBING
J 0
(-6275 4375);
DISPLAY 0.872340 (-6275 4375);
PAINT GREEN (-6275 4375);
DISPLAY INVISIBLE (-6275 4375);
FORCEPROP 1 LAST HDL_TAP TRUE
J 0
(-5950 4200);
DISPLAY 0.872340 (-5950 4200);
DISPLAY INVISIBLE (-5950 4200);
FORCEPROP 1 LAST PATH I246
J 0
(-6277 4325);
DISPLAY 0.872340 (-6277 4325);
PAINT GREEN (-6277 4325);
DISPLAY INVISIBLE (-6277 4325);
FORCEADD TAP..1
(-6275 4425);
FORCEPROP 3 LASTPIN (-6325 4425) SIG_NAME M_E_CPU0_SA_DQ<8>
J 0
(-6315 4435);
DISPLAY 0.659574 (-6315 4435);
PAINT MONO (-6315 4435);
DISPLAY INVISIBLE (-6315 4435);
FORCEPROP 1 LASTPIN (-6325 4425) BN 8
J 0
(-6337 4433);
DISPLAY 0.489362 (-6337 4433);
PAINT GREEN (-6337 4433);
FORCEPROP 2 LAST CDS_LIB mstr_standard
J 0
(-6275 4425);
DISPLAY 0.723404 (-6275 4425);
PAINT MONO (-6275 4425);
DISPLAY INVISIBLE (-6275 4425);
FORCEPROP 1 LAST BODY_TYPE PLUMBING
J 0
(-6275 4475);
DISPLAY 0.872340 (-6275 4475);
PAINT GREEN (-6275 4475);
DISPLAY INVISIBLE (-6275 4475);
FORCEPROP 1 LAST HDL_TAP TRUE
J 0
(-5950 4300);
DISPLAY 0.872340 (-5950 4300);
DISPLAY INVISIBLE (-5950 4300);
FORCEPROP 1 LAST PATH I247
J 0
(-6277 4425);
DISPLAY 0.872340 (-6277 4425);
PAINT GREEN (-6277 4425);
DISPLAY INVISIBLE (-6277 4425);
FORCEADD TAP..1
(-6275 4475);
FORCEPROP 3 LASTPIN (-6325 4475) SIG_NAME M_E_CPU0_SA_DQ<9>
J 0
(-6315 4485);
DISPLAY 0.659574 (-6315 4485);
PAINT MONO (-6315 4485);
DISPLAY INVISIBLE (-6315 4485);
FORCEPROP 1 LASTPIN (-6325 4475) BN 9
J 0
(-6337 4483);
DISPLAY 0.489362 (-6337 4483);
PAINT GREEN (-6337 4483);
FORCEPROP 2 LAST CDS_LIB mstr_standard
J 0
(-6275 4475);
DISPLAY 0.723404 (-6275 4475);
PAINT MONO (-6275 4475);
DISPLAY INVISIBLE (-6275 4475);
FORCEPROP 1 LAST BODY_TYPE PLUMBING
J 0
(-6275 4525);
DISPLAY 0.872340 (-6275 4525);
PAINT GREEN (-6275 4525);
DISPLAY INVISIBLE (-6275 4525);
FORCEPROP 1 LAST HDL_TAP TRUE
J 0
(-5950 4350);
DISPLAY 0.872340 (-5950 4350);
DISPLAY INVISIBLE (-5950 4350);
FORCEPROP 1 LAST PATH I248
J 0
(-6277 4475);
DISPLAY 0.872340 (-6277 4475);
PAINT GREEN (-6277 4475);
DISPLAY INVISIBLE (-6277 4475);
FORCEADD TAP..1
(-6275 4525);
FORCEPROP 3 LASTPIN (-6325 4525) SIG_NAME M_E_CPU0_SA_DQ<10>
J 0
(-6315 4535);
DISPLAY 0.659574 (-6315 4535);
PAINT MONO (-6315 4535);
DISPLAY INVISIBLE (-6315 4535);
FORCEPROP 1 LASTPIN (-6325 4525) BN 10
J 0
(-6337 4533);
DISPLAY 0.489362 (-6337 4533);
PAINT GREEN (-6337 4533);
FORCEPROP 2 LAST CDS_LIB mstr_standard
J 0
(-6275 4525);
DISPLAY 0.723404 (-6275 4525);
PAINT MONO (-6275 4525);
DISPLAY INVISIBLE (-6275 4525);
FORCEPROP 1 LAST BODY_TYPE PLUMBING
J 0
(-6275 4575);
DISPLAY 0.872340 (-6275 4575);
PAINT GREEN (-6275 4575);
DISPLAY INVISIBLE (-6275 4575);
FORCEPROP 1 LAST HDL_TAP TRUE
J 0
(-5950 4400);
DISPLAY 0.872340 (-5950 4400);
DISPLAY INVISIBLE (-5950 4400);
FORCEPROP 1 LAST PATH I249
J 0
(-6277 4525);
DISPLAY 0.872340 (-6277 4525);
PAINT GREEN (-6277 4525);
DISPLAY INVISIBLE (-6277 4525);
FORCEADD TAP..1
(-6275 4725);
FORCEPROP 3 LASTPIN (-6325 4725) SIG_NAME M_E_CPU0_SA_DQ<14>
J 0
(-6315 4735);
DISPLAY 0.659574 (-6315 4735);
PAINT MONO (-6315 4735);
DISPLAY INVISIBLE (-6315 4735);
FORCEPROP 1 LASTPIN (-6325 4725) BN 14
J 0
(-6337 4733);
DISPLAY 0.489362 (-6337 4733);
PAINT GREEN (-6337 4733);
FORCEPROP 2 LAST CDS_LIB mstr_standard
J 0
(-6275 4725);
DISPLAY 0.723404 (-6275 4725);
PAINT MONO (-6275 4725);
DISPLAY INVISIBLE (-6275 4725);
FORCEPROP 1 LAST BODY_TYPE PLUMBING
J 0
(-6275 4775);
DISPLAY 0.872340 (-6275 4775);
PAINT GREEN (-6275 4775);
DISPLAY INVISIBLE (-6275 4775);
FORCEPROP 1 LAST HDL_TAP TRUE
J 0
(-5950 4600);
DISPLAY 0.872340 (-5950 4600);
DISPLAY INVISIBLE (-5950 4600);
FORCEPROP 1 LAST PATH I250
J 0
(-6277 4725);
DISPLAY 0.872340 (-6277 4725);
PAINT GREEN (-6277 4725);
DISPLAY INVISIBLE (-6277 4725);
FORCEADD TAP..1
(-6275 4775);
FORCEPROP 3 LASTPIN (-6325 4775) SIG_NAME M_E_CPU0_SA_DQ<15>
J 0
(-6315 4785);
DISPLAY 0.659574 (-6315 4785);
PAINT MONO (-6315 4785);
DISPLAY INVISIBLE (-6315 4785);
FORCEPROP 1 LASTPIN (-6325 4775) BN 15
J 0
(-6337 4783);
DISPLAY 0.489362 (-6337 4783);
PAINT GREEN (-6337 4783);
FORCEPROP 2 LAST CDS_LIB mstr_standard
J 0
(-6275 4775);
DISPLAY 0.723404 (-6275 4775);
PAINT MONO (-6275 4775);
DISPLAY INVISIBLE (-6275 4775);
FORCEPROP 1 LAST BODY_TYPE PLUMBING
J 0
(-6275 4825);
DISPLAY 0.872340 (-6275 4825);
PAINT GREEN (-6275 4825);
DISPLAY INVISIBLE (-6275 4825);
FORCEPROP 1 LAST HDL_TAP TRUE
J 0
(-5950 4650);
DISPLAY 0.872340 (-5950 4650);
DISPLAY INVISIBLE (-5950 4650);
FORCEPROP 1 LAST PATH I251
J 0
(-6277 4775);
DISPLAY 0.872340 (-6277 4775);
PAINT GREEN (-6277 4775);
DISPLAY INVISIBLE (-6277 4775);
FORCEADD TAP..1
(-6275 4675);
FORCEPROP 3 LASTPIN (-6325 4675) SIG_NAME M_E_CPU0_SA_DQ<13>
J 0
(-6315 4685);
DISPLAY 0.659574 (-6315 4685);
PAINT MONO (-6315 4685);
DISPLAY INVISIBLE (-6315 4685);
FORCEPROP 1 LASTPIN (-6325 4675) BN 13
J 0
(-6337 4683);
DISPLAY 0.489362 (-6337 4683);
PAINT GREEN (-6337 4683);
FORCEPROP 2 LAST CDS_LIB mstr_standard
J 0
(-6275 4675);
DISPLAY 0.723404 (-6275 4675);
PAINT MONO (-6275 4675);
DISPLAY INVISIBLE (-6275 4675);
FORCEPROP 1 LAST BODY_TYPE PLUMBING
J 0
(-6275 4725);
DISPLAY 0.872340 (-6275 4725);
PAINT GREEN (-6275 4725);
DISPLAY INVISIBLE (-6275 4725);
FORCEPROP 1 LAST HDL_TAP TRUE
J 0
(-5950 4550);
DISPLAY 0.872340 (-5950 4550);
DISPLAY INVISIBLE (-5950 4550);
FORCEPROP 1 LAST PATH I252
J 0
(-6277 4675);
DISPLAY 0.872340 (-6277 4675);
PAINT GREEN (-6277 4675);
DISPLAY INVISIBLE (-6277 4675);
FORCEADD TAP..1
(-6275 4625);
FORCEPROP 3 LASTPIN (-6325 4625) SIG_NAME M_E_CPU0_SA_DQ<12>
J 0
(-6315 4635);
DISPLAY 0.659574 (-6315 4635);
PAINT MONO (-6315 4635);
DISPLAY INVISIBLE (-6315 4635);
FORCEPROP 1 LASTPIN (-6325 4625) BN 12
J 0
(-6337 4633);
DISPLAY 0.489362 (-6337 4633);
PAINT GREEN (-6337 4633);
FORCEPROP 2 LAST CDS_LIB mstr_standard
J 0
(-6275 4625);
DISPLAY 0.723404 (-6275 4625);
PAINT MONO (-6275 4625);
DISPLAY INVISIBLE (-6275 4625);
FORCEPROP 1 LAST BODY_TYPE PLUMBING
J 0
(-6275 4675);
DISPLAY 0.872340 (-6275 4675);
PAINT GREEN (-6275 4675);
DISPLAY INVISIBLE (-6275 4675);
FORCEPROP 1 LAST HDL_TAP TRUE
J 0
(-5950 4500);
DISPLAY 0.872340 (-5950 4500);
DISPLAY INVISIBLE (-5950 4500);
FORCEPROP 1 LAST PATH I253
J 0
(-6277 4625);
DISPLAY 0.872340 (-6277 4625);
PAINT GREEN (-6277 4625);
DISPLAY INVISIBLE (-6277 4625);
FORCEADD TAP..1
(-6275 4575);
FORCEPROP 3 LASTPIN (-6325 4575) SIG_NAME M_E_CPU0_SA_DQ<11>
J 0
(-6315 4585);
DISPLAY 0.659574 (-6315 4585);
PAINT MONO (-6315 4585);
DISPLAY INVISIBLE (-6315 4585);
FORCEPROP 1 LASTPIN (-6325 4575) BN 11
J 0
(-6337 4583);
DISPLAY 0.489362 (-6337 4583);
PAINT GREEN (-6337 4583);
FORCEPROP 2 LAST CDS_LIB mstr_standard
J 0
(-6275 4575);
DISPLAY 0.723404 (-6275 4575);
PAINT MONO (-6275 4575);
DISPLAY INVISIBLE (-6275 4575);
FORCEPROP 1 LAST BODY_TYPE PLUMBING
J 0
(-6275 4625);
DISPLAY 0.872340 (-6275 4625);
PAINT GREEN (-6275 4625);
DISPLAY INVISIBLE (-6275 4625);
FORCEPROP 1 LAST HDL_TAP TRUE
J 0
(-5950 4450);
DISPLAY 0.872340 (-5950 4450);
DISPLAY INVISIBLE (-5950 4450);
FORCEPROP 1 LAST PATH I254
J 0
(-6277 4575);
DISPLAY 0.872340 (-6277 4575);
PAINT GREEN (-6277 4575);
DISPLAY INVISIBLE (-6277 4575);
FORCEADD TAP..1
(-6275 4875);
FORCEPROP 3 LASTPIN (-6325 4875) SIG_NAME M_E_CPU0_SA_DQ<17>
J 0
(-6315 4885);
DISPLAY 0.659574 (-6315 4885);
PAINT MONO (-6315 4885);
DISPLAY INVISIBLE (-6315 4885);
FORCEPROP 1 LASTPIN (-6325 4875) BN 17
J 0
(-6337 4883);
DISPLAY 0.489362 (-6337 4883);
PAINT GREEN (-6337 4883);
FORCEPROP 2 LAST CDS_LIB mstr_standard
J 0
(-6275 4875);
DISPLAY 0.723404 (-6275 4875);
PAINT MONO (-6275 4875);
DISPLAY INVISIBLE (-6275 4875);
FORCEPROP 1 LAST BODY_TYPE PLUMBING
J 0
(-6275 4925);
DISPLAY 0.872340 (-6275 4925);
PAINT GREEN (-6275 4925);
DISPLAY INVISIBLE (-6275 4925);
FORCEPROP 1 LAST HDL_TAP TRUE
J 0
(-5950 4750);
DISPLAY 0.872340 (-5950 4750);
DISPLAY INVISIBLE (-5950 4750);
FORCEPROP 1 LAST PATH I255
J 0
(-6277 4875);
DISPLAY 0.872340 (-6277 4875);
PAINT GREEN (-6277 4875);
DISPLAY INVISIBLE (-6277 4875);
FORCEADD TAP..1
(-6275 4925);
FORCEPROP 3 LASTPIN (-6325 4925) SIG_NAME M_E_CPU0_SA_DQ<18>
J 0
(-6315 4935);
DISPLAY 0.659574 (-6315 4935);
PAINT MONO (-6315 4935);
DISPLAY INVISIBLE (-6315 4935);
FORCEPROP 1 LASTPIN (-6325 4925) BN 18
J 0
(-6337 4933);
DISPLAY 0.489362 (-6337 4933);
PAINT GREEN (-6337 4933);
FORCEPROP 2 LAST CDS_LIB mstr_standard
J 0
(-6275 4925);
DISPLAY 0.723404 (-6275 4925);
PAINT MONO (-6275 4925);
DISPLAY INVISIBLE (-6275 4925);
FORCEPROP 1 LAST BODY_TYPE PLUMBING
J 0
(-6275 4975);
DISPLAY 0.872340 (-6275 4975);
PAINT GREEN (-6275 4975);
DISPLAY INVISIBLE (-6275 4975);
FORCEPROP 1 LAST HDL_TAP TRUE
J 0
(-5950 4800);
DISPLAY 0.872340 (-5950 4800);
DISPLAY INVISIBLE (-5950 4800);
FORCEPROP 1 LAST PATH I256
J 0
(-6277 4925);
DISPLAY 0.872340 (-6277 4925);
PAINT GREEN (-6277 4925);
DISPLAY INVISIBLE (-6277 4925);
FORCEADD TAP..1
(-6275 4825);
FORCEPROP 3 LASTPIN (-6325 4825) SIG_NAME M_E_CPU0_SA_DQ<16>
J 0
(-6315 4835);
DISPLAY 0.659574 (-6315 4835);
PAINT MONO (-6315 4835);
DISPLAY INVISIBLE (-6315 4835);
FORCEPROP 1 LASTPIN (-6325 4825) BN 16
J 0
(-6337 4833);
DISPLAY 0.489362 (-6337 4833);
PAINT GREEN (-6337 4833);
FORCEPROP 2 LAST CDS_LIB mstr_standard
J 0
(-6275 4825);
DISPLAY 0.723404 (-6275 4825);
PAINT MONO (-6275 4825);
DISPLAY INVISIBLE (-6275 4825);
FORCEPROP 1 LAST BODY_TYPE PLUMBING
J 0
(-6275 4875);
DISPLAY 0.872340 (-6275 4875);
PAINT GREEN (-6275 4875);
DISPLAY INVISIBLE (-6275 4875);
FORCEPROP 1 LAST HDL_TAP TRUE
J 0
(-5950 4700);
DISPLAY 0.872340 (-5950 4700);
DISPLAY INVISIBLE (-5950 4700);
FORCEPROP 1 LAST PATH I257
J 0
(-6277 4825);
DISPLAY 0.872340 (-6277 4825);
PAINT GREEN (-6277 4825);
DISPLAY INVISIBLE (-6277 4825);
FORCEADD TAP..1
(-6275 5025);
FORCEPROP 3 LASTPIN (-6325 5025) SIG_NAME M_E_CPU0_SA_DQ<20>
J 0
(-6315 5035);
DISPLAY 0.659574 (-6315 5035);
PAINT MONO (-6315 5035);
DISPLAY INVISIBLE (-6315 5035);
FORCEPROP 1 LASTPIN (-6325 5025) BN 20
J 0
(-6337 5033);
DISPLAY 0.489362 (-6337 5033);
PAINT GREEN (-6337 5033);
FORCEPROP 2 LAST CDS_LIB mstr_standard
J 0
(-6275 5025);
DISPLAY 0.723404 (-6275 5025);
PAINT MONO (-6275 5025);
DISPLAY INVISIBLE (-6275 5025);
FORCEPROP 1 LAST BODY_TYPE PLUMBING
J 0
(-6275 5075);
DISPLAY 0.872340 (-6275 5075);
PAINT GREEN (-6275 5075);
DISPLAY INVISIBLE (-6275 5075);
FORCEPROP 1 LAST HDL_TAP TRUE
J 0
(-5950 4900);
DISPLAY 0.872340 (-5950 4900);
DISPLAY INVISIBLE (-5950 4900);
FORCEPROP 1 LAST PATH I258
J 0
(-6277 5025);
DISPLAY 0.872340 (-6277 5025);
PAINT GREEN (-6277 5025);
DISPLAY INVISIBLE (-6277 5025);
FORCEADD TAP..1
(-6275 4975);
FORCEPROP 3 LASTPIN (-6325 4975) SIG_NAME M_E_CPU0_SA_DQ<19>
J 0
(-6315 4985);
DISPLAY 0.659574 (-6315 4985);
PAINT MONO (-6315 4985);
DISPLAY INVISIBLE (-6315 4985);
FORCEPROP 1 LASTPIN (-6325 4975) BN 19
J 0
(-6337 4983);
DISPLAY 0.489362 (-6337 4983);
PAINT GREEN (-6337 4983);
FORCEPROP 2 LAST CDS_LIB mstr_standard
J 0
(-6275 4975);
DISPLAY 0.723404 (-6275 4975);
PAINT MONO (-6275 4975);
DISPLAY INVISIBLE (-6275 4975);
FORCEPROP 1 LAST BODY_TYPE PLUMBING
J 0
(-6275 5025);
DISPLAY 0.872340 (-6275 5025);
PAINT GREEN (-6275 5025);
DISPLAY INVISIBLE (-6275 5025);
FORCEPROP 1 LAST HDL_TAP TRUE
J 0
(-5950 4850);
DISPLAY 0.872340 (-5950 4850);
DISPLAY INVISIBLE (-5950 4850);
FORCEPROP 1 LAST PATH I259
J 0
(-6277 4975);
DISPLAY 0.872340 (-6277 4975);
PAINT GREEN (-6277 4975);
DISPLAY INVISIBLE (-6277 4975);
FORCEADD OFFPAGE..3
(-5625 4000);
FORCEPROP 2 LAST $XR0 14 
J 0
(-5411 4000);
DISPLAY 0.638298 (-5411 4000);
PAINT MONO (-5411 4000);
FORCEPROP 2 LAST PATH I260
J 0
(-5300 4050);
DISPLAY 0.808511 (-5300 4050);
DISPLAY INVISIBLE (-5300 4050);
FORCEPROP 1 LAST COMMENT_BODY TRUE
J 0
(-5675 3900);
DISPLAY 0.872340 (-5675 3900);
PAINT GREEN (-5675 3900);
DISPLAY INVISIBLE (-5675 3900);
FORCEPROP 1 LAST OFFPAGE TRUE
J 0
(-5300 3875);
DISPLAY 0.872340 (-5300 3875);
PAINT GREEN (-5300 3875);
DISPLAY INVISIBLE (-5300 3875);
FORCEPROP 2 LAST CDS_LIB mstr_standard
J 0
(-5625 4000);
DISPLAY 0.723404 (-5625 4000);
PAINT MONO (-5625 4000);
DISPLAY INVISIBLE (-5625 4000);
FORCEADD OFFPAGE..1
(-8575 5225);
FORCEPROP 2 LAST $XR0 14 
J 0
(-8826 5225);
DISPLAY 0.638298 (-8826 5225);
PAINT MONO (-8826 5225);
FORCEPROP 2 LAST PATH I261
J 0
(-8525 5300);
DISPLAY 0.808511 (-8525 5300);
DISPLAY INVISIBLE (-8525 5300);
FORCEPROP 1 LAST COMMENT_BODY TRUE
J 0
(-8450 5125);
DISPLAY 0.872340 (-8450 5125);
PAINT GREEN (-8450 5125);
DISPLAY INVISIBLE (-8450 5125);
FORCEPROP 1 LAST OFFPAGE TRUE
J 0
(-8250 5100);
DISPLAY 0.872340 (-8250 5100);
PAINT GREEN (-8250 5100);
DISPLAY INVISIBLE (-8250 5100);
FORCEPROP 2 LAST CDS_LIB mstr_standard
J 0
(-8575 5225);
DISPLAY 0.723404 (-8575 5225);
PAINT MONO (-8575 5225);
DISPLAY INVISIBLE (-8575 5225);
FORCEADD OFFPAGE..1
(-8575 5625);
FORCEPROP 2 LAST $XR0 14 
J 0
(-8826 5625);
DISPLAY 0.638298 (-8826 5625);
PAINT MONO (-8826 5625);
FORCEPROP 2 LAST PATH I262
J 0
(-8525 5700);
DISPLAY 0.808511 (-8525 5700);
DISPLAY INVISIBLE (-8525 5700);
FORCEPROP 1 LAST COMMENT_BODY TRUE
J 0
(-8450 5525);
DISPLAY 0.872340 (-8450 5525);
PAINT GREEN (-8450 5525);
DISPLAY INVISIBLE (-8450 5525);
FORCEPROP 1 LAST OFFPAGE TRUE
J 0
(-8250 5500);
DISPLAY 0.872340 (-8250 5500);
PAINT GREEN (-8250 5500);
DISPLAY INVISIBLE (-8250 5500);
FORCEPROP 2 LAST CDS_LIB mstr_standard
J 0
(-8575 5625);
DISPLAY 0.723404 (-8575 5625);
PAINT MONO (-8575 5625);
DISPLAY INVISIBLE (-8575 5625);
FORCEADD TAP..1
R 2
(-7975 5175);
FORCEPROP 3 LASTPIN (-7925 5175) SIG_NAME M_E_CPU0_SB_CA<6>
J 0
(-7915 5185);
DISPLAY 0.659574 (-7915 5185);
PAINT MONO (-7915 5185);
DISPLAY INVISIBLE (-7915 5185);
FORCEPROP 1 LASTPIN (-7925 5175) BN 6
J 2
(-7913 5183);
DISPLAY 0.489362 (-7913 5183);
PAINT GREEN (-7913 5183);
FORCEPROP 2 LAST CDS_LIB mstr_standard
J 0
(-7975 5175);
DISPLAY 0.723404 (-7975 5175);
PAINT MONO (-7975 5175);
DISPLAY INVISIBLE (-7975 5175);
FORCEPROP 1 LAST BODY_TYPE PLUMBING
J 2
(-7975 5225);
DISPLAY 0.872340 (-7975 5225);
PAINT GREEN (-7975 5225);
DISPLAY INVISIBLE (-7975 5225);
FORCEPROP 1 LAST HDL_TAP TRUE
J 2
(-8300 5050);
DISPLAY 0.872340 (-8300 5050);
DISPLAY INVISIBLE (-8300 5050);
FORCEPROP 1 LAST PATH I263
J 2
(-7973 5175);
DISPLAY 0.872340 (-7973 5175);
PAINT GREEN (-7973 5175);
DISPLAY INVISIBLE (-7973 5175);
FORCEADD TAP..1
R 2
(-7975 5075);
FORCEPROP 3 LASTPIN (-7925 5075) SIG_NAME M_E_CPU0_SB_CA<4>
J 0
(-7915 5085);
DISPLAY 0.659574 (-7915 5085);
PAINT MONO (-7915 5085);
DISPLAY INVISIBLE (-7915 5085);
FORCEPROP 1 LASTPIN (-7925 5075) BN 4
J 2
(-7913 5083);
DISPLAY 0.489362 (-7913 5083);
PAINT GREEN (-7913 5083);
FORCEPROP 2 LAST CDS_LIB mstr_standard
J 0
(-7975 5075);
DISPLAY 0.723404 (-7975 5075);
PAINT MONO (-7975 5075);
DISPLAY INVISIBLE (-7975 5075);
FORCEPROP 1 LAST BODY_TYPE PLUMBING
J 2
(-7975 5125);
DISPLAY 0.872340 (-7975 5125);
PAINT GREEN (-7975 5125);
DISPLAY INVISIBLE (-7975 5125);
FORCEPROP 1 LAST HDL_TAP TRUE
J 2
(-8300 4950);
DISPLAY 0.872340 (-8300 4950);
DISPLAY INVISIBLE (-8300 4950);
FORCEPROP 1 LAST PATH I264
J 2
(-7973 5075);
DISPLAY 0.872340 (-7973 5075);
PAINT GREEN (-7973 5075);
DISPLAY INVISIBLE (-7973 5075);
FORCEADD TAP..1
R 2
(-7975 5125);
FORCEPROP 3 LASTPIN (-7925 5125) SIG_NAME M_E_CPU0_SB_CA<5>
J 0
(-7915 5135);
DISPLAY 0.659574 (-7915 5135);
PAINT MONO (-7915 5135);
DISPLAY INVISIBLE (-7915 5135);
FORCEPROP 1 LASTPIN (-7925 5125) BN 5
J 2
(-7913 5133);
DISPLAY 0.489362 (-7913 5133);
PAINT GREEN (-7913 5133);
FORCEPROP 2 LAST CDS_LIB mstr_standard
J 0
(-7975 5125);
DISPLAY 0.723404 (-7975 5125);
PAINT MONO (-7975 5125);
DISPLAY INVISIBLE (-7975 5125);
FORCEPROP 1 LAST BODY_TYPE PLUMBING
J 2
(-7975 5175);
DISPLAY 0.872340 (-7975 5175);
PAINT GREEN (-7975 5175);
DISPLAY INVISIBLE (-7975 5175);
FORCEPROP 1 LAST HDL_TAP TRUE
J 2
(-8300 5000);
DISPLAY 0.872340 (-8300 5000);
DISPLAY INVISIBLE (-8300 5000);
FORCEPROP 1 LAST PATH I265
J 2
(-7973 5125);
DISPLAY 0.872340 (-7973 5125);
PAINT GREEN (-7973 5125);
DISPLAY INVISIBLE (-7973 5125);
FORCEADD TAP..1
R 2
(-7975 5275);
FORCEPROP 3 LASTPIN (-7925 5275) SIG_NAME M_E_CPU0_SA_CA<0>
J 0
(-7915 5285);
DISPLAY 0.659574 (-7915 5285);
PAINT MONO (-7915 5285);
DISPLAY INVISIBLE (-7915 5285);
FORCEPROP 1 LASTPIN (-7925 5275) BN 0
J 2
(-7913 5283);
DISPLAY 0.489362 (-7913 5283);
PAINT GREEN (-7913 5283);
FORCEPROP 2 LAST CDS_LIB mstr_standard
J 0
(-7975 5275);
DISPLAY 0.723404 (-7975 5275);
PAINT MONO (-7975 5275);
DISPLAY INVISIBLE (-7975 5275);
FORCEPROP 1 LAST BODY_TYPE PLUMBING
J 2
(-7975 5325);
DISPLAY 0.872340 (-7975 5325);
PAINT GREEN (-7975 5325);
DISPLAY INVISIBLE (-7975 5325);
FORCEPROP 1 LAST HDL_TAP TRUE
J 2
(-8300 5150);
DISPLAY 0.872340 (-8300 5150);
DISPLAY INVISIBLE (-8300 5150);
FORCEPROP 1 LAST PATH I266
J 2
(-7973 5275);
DISPLAY 0.872340 (-7973 5275);
PAINT GREEN (-7973 5275);
DISPLAY INVISIBLE (-7973 5275);
FORCEADD TAP..1
R 2
(-7975 5325);
FORCEPROP 3 LASTPIN (-7925 5325) SIG_NAME M_E_CPU0_SA_CA<1>
J 0
(-7915 5335);
DISPLAY 0.659574 (-7915 5335);
PAINT MONO (-7915 5335);
DISPLAY INVISIBLE (-7915 5335);
FORCEPROP 1 LASTPIN (-7925 5325) BN 1
J 2
(-7913 5333);
DISPLAY 0.489362 (-7913 5333);
PAINT GREEN (-7913 5333);
FORCEPROP 2 LAST CDS_LIB mstr_standard
J 0
(-7975 5325);
DISPLAY 0.723404 (-7975 5325);
PAINT MONO (-7975 5325);
DISPLAY INVISIBLE (-7975 5325);
FORCEPROP 1 LAST BODY_TYPE PLUMBING
J 2
(-7975 5375);
DISPLAY 0.872340 (-7975 5375);
PAINT GREEN (-7975 5375);
DISPLAY INVISIBLE (-7975 5375);
FORCEPROP 1 LAST HDL_TAP TRUE
J 2
(-8300 5200);
DISPLAY 0.872340 (-8300 5200);
DISPLAY INVISIBLE (-8300 5200);
FORCEPROP 1 LAST PATH I267
J 2
(-7973 5325);
DISPLAY 0.872340 (-7973 5325);
PAINT GREEN (-7973 5325);
DISPLAY INVISIBLE (-7973 5325);
FORCEADD TAP..1
R 2
(-7975 5375);
FORCEPROP 3 LASTPIN (-7925 5375) SIG_NAME M_E_CPU0_SA_CA<2>
J 0
(-7915 5385);
DISPLAY 0.659574 (-7915 5385);
PAINT MONO (-7915 5385);
DISPLAY INVISIBLE (-7915 5385);
FORCEPROP 1 LASTPIN (-7925 5375) BN 2
J 2
(-7913 5383);
DISPLAY 0.489362 (-7913 5383);
PAINT GREEN (-7913 5383);
FORCEPROP 2 LAST CDS_LIB mstr_standard
J 0
(-7975 5375);
DISPLAY 0.723404 (-7975 5375);
PAINT MONO (-7975 5375);
DISPLAY INVISIBLE (-7975 5375);
FORCEPROP 1 LAST BODY_TYPE PLUMBING
J 2
(-7975 5425);
DISPLAY 0.872340 (-7975 5425);
PAINT GREEN (-7975 5425);
DISPLAY INVISIBLE (-7975 5425);
FORCEPROP 1 LAST HDL_TAP TRUE
J 2
(-8300 5250);
DISPLAY 0.872340 (-8300 5250);
DISPLAY INVISIBLE (-8300 5250);
FORCEPROP 1 LAST PATH I268
J 2
(-7973 5375);
DISPLAY 0.872340 (-7973 5375);
PAINT GREEN (-7973 5375);
DISPLAY INVISIBLE (-7973 5375);
FORCEADD TAP..1
R 2
(-7975 5425);
FORCEPROP 3 LASTPIN (-7925 5425) SIG_NAME M_E_CPU0_SA_CA<3>
J 0
(-7915 5435);
DISPLAY 0.659574 (-7915 5435);
PAINT MONO (-7915 5435);
DISPLAY INVISIBLE (-7915 5435);
FORCEPROP 1 LASTPIN (-7925 5425) BN 3
J 2
(-7913 5433);
DISPLAY 0.489362 (-7913 5433);
PAINT GREEN (-7913 5433);
FORCEPROP 2 LAST CDS_LIB mstr_standard
J 0
(-7975 5425);
DISPLAY 0.723404 (-7975 5425);
PAINT MONO (-7975 5425);
DISPLAY INVISIBLE (-7975 5425);
FORCEPROP 1 LAST BODY_TYPE PLUMBING
J 2
(-7975 5475);
DISPLAY 0.872340 (-7975 5475);
PAINT GREEN (-7975 5475);
DISPLAY INVISIBLE (-7975 5475);
FORCEPROP 1 LAST HDL_TAP TRUE
J 2
(-8300 5300);
DISPLAY 0.872340 (-8300 5300);
DISPLAY INVISIBLE (-8300 5300);
FORCEPROP 1 LAST PATH I269
J 2
(-7973 5425);
DISPLAY 0.872340 (-7973 5425);
PAINT GREEN (-7973 5425);
DISPLAY INVISIBLE (-7973 5425);
FORCEADD TAP..1
R 2
(-7975 5525);
FORCEPROP 3 LASTPIN (-7925 5525) SIG_NAME M_E_CPU0_SA_CA<5>
J 0
(-7915 5535);
DISPLAY 0.659574 (-7915 5535);
PAINT MONO (-7915 5535);
DISPLAY INVISIBLE (-7915 5535);
FORCEPROP 1 LASTPIN (-7925 5525) BN 5
J 2
(-7913 5533);
DISPLAY 0.489362 (-7913 5533);
PAINT GREEN (-7913 5533);
FORCEPROP 2 LAST CDS_LIB mstr_standard
J 0
(-7975 5525);
DISPLAY 0.723404 (-7975 5525);
PAINT MONO (-7975 5525);
DISPLAY INVISIBLE (-7975 5525);
FORCEPROP 1 LAST BODY_TYPE PLUMBING
J 2
(-7975 5575);
DISPLAY 0.872340 (-7975 5575);
PAINT GREEN (-7975 5575);
DISPLAY INVISIBLE (-7975 5575);
FORCEPROP 1 LAST HDL_TAP TRUE
J 2
(-8300 5400);
DISPLAY 0.872340 (-8300 5400);
DISPLAY INVISIBLE (-8300 5400);
FORCEPROP 1 LAST PATH I270
J 2
(-7973 5525);
DISPLAY 0.872340 (-7973 5525);
PAINT GREEN (-7973 5525);
DISPLAY INVISIBLE (-7973 5525);
FORCEADD TAP..1
R 2
(-7975 5475);
FORCEPROP 3 LASTPIN (-7925 5475) SIG_NAME M_E_CPU0_SA_CA<4>
J 0
(-7915 5485);
DISPLAY 0.659574 (-7915 5485);
PAINT MONO (-7915 5485);
DISPLAY INVISIBLE (-7915 5485);
FORCEPROP 1 LASTPIN (-7925 5475) BN 4
J 2
(-7913 5483);
DISPLAY 0.489362 (-7913 5483);
PAINT GREEN (-7913 5483);
FORCEPROP 2 LAST CDS_LIB mstr_standard
J 0
(-7975 5475);
DISPLAY 0.723404 (-7975 5475);
PAINT MONO (-7975 5475);
DISPLAY INVISIBLE (-7975 5475);
FORCEPROP 1 LAST BODY_TYPE PLUMBING
J 2
(-7975 5525);
DISPLAY 0.872340 (-7975 5525);
PAINT GREEN (-7975 5525);
DISPLAY INVISIBLE (-7975 5525);
FORCEPROP 1 LAST HDL_TAP TRUE
J 2
(-8300 5350);
DISPLAY 0.872340 (-8300 5350);
DISPLAY INVISIBLE (-8300 5350);
FORCEPROP 1 LAST PATH I271
J 2
(-7973 5475);
DISPLAY 0.872340 (-7973 5475);
PAINT GREEN (-7973 5475);
DISPLAY INVISIBLE (-7973 5475);
FORCEADD TAP..1
R 2
(-7975 5575);
FORCEPROP 3 LASTPIN (-7925 5575) SIG_NAME M_E_CPU0_SA_CA<6>
J 0
(-7915 5585);
DISPLAY 0.659574 (-7915 5585);
PAINT MONO (-7915 5585);
DISPLAY INVISIBLE (-7915 5585);
FORCEPROP 1 LASTPIN (-7925 5575) BN 6
J 2
(-7913 5583);
DISPLAY 0.489362 (-7913 5583);
PAINT GREEN (-7913 5583);
FORCEPROP 2 LAST CDS_LIB mstr_standard
J 0
(-7975 5575);
DISPLAY 0.723404 (-7975 5575);
PAINT MONO (-7975 5575);
DISPLAY INVISIBLE (-7975 5575);
FORCEPROP 1 LAST BODY_TYPE PLUMBING
J 2
(-7975 5625);
DISPLAY 0.872340 (-7975 5625);
PAINT GREEN (-7975 5625);
DISPLAY INVISIBLE (-7975 5625);
FORCEPROP 1 LAST HDL_TAP TRUE
J 2
(-8300 5450);
DISPLAY 0.872340 (-8300 5450);
DISPLAY INVISIBLE (-8300 5450);
FORCEPROP 1 LAST PATH I272
J 2
(-7973 5575);
DISPLAY 0.872340 (-7973 5575);
PAINT GREEN (-7973 5575);
DISPLAY INVISIBLE (-7973 5575);
FORCEADD TAP..1
(-6275 5175);
FORCEPROP 3 LASTPIN (-6325 5175) SIG_NAME M_E_CPU0_SA_DQ<23>
J 0
(-6315 5185);
DISPLAY 0.659574 (-6315 5185);
PAINT MONO (-6315 5185);
DISPLAY INVISIBLE (-6315 5185);
FORCEPROP 1 LASTPIN (-6325 5175) BN 23
J 0
(-6337 5183);
DISPLAY 0.489362 (-6337 5183);
PAINT GREEN (-6337 5183);
FORCEPROP 2 LAST CDS_LIB mstr_standard
J 0
(-6275 5175);
DISPLAY 0.723404 (-6275 5175);
PAINT MONO (-6275 5175);
DISPLAY INVISIBLE (-6275 5175);
FORCEPROP 1 LAST BODY_TYPE PLUMBING
J 0
(-6275 5225);
DISPLAY 0.872340 (-6275 5225);
PAINT GREEN (-6275 5225);
DISPLAY INVISIBLE (-6275 5225);
FORCEPROP 1 LAST HDL_TAP TRUE
J 0
(-5950 5050);
DISPLAY 0.872340 (-5950 5050);
DISPLAY INVISIBLE (-5950 5050);
FORCEPROP 1 LAST PATH I273
J 0
(-6277 5175);
DISPLAY 0.872340 (-6277 5175);
PAINT GREEN (-6277 5175);
DISPLAY INVISIBLE (-6277 5175);
FORCEADD TAP..1
(-6275 5075);
FORCEPROP 3 LASTPIN (-6325 5075) SIG_NAME M_E_CPU0_SA_DQ<21>
J 0
(-6315 5085);
DISPLAY 0.659574 (-6315 5085);
PAINT MONO (-6315 5085);
DISPLAY INVISIBLE (-6315 5085);
FORCEPROP 1 LASTPIN (-6325 5075) BN 21
J 0
(-6337 5083);
DISPLAY 0.489362 (-6337 5083);
PAINT GREEN (-6337 5083);
FORCEPROP 2 LAST CDS_LIB mstr_standard
J 0
(-6275 5075);
DISPLAY 0.723404 (-6275 5075);
PAINT MONO (-6275 5075);
DISPLAY INVISIBLE (-6275 5075);
FORCEPROP 1 LAST BODY_TYPE PLUMBING
J 0
(-6275 5125);
DISPLAY 0.872340 (-6275 5125);
PAINT GREEN (-6275 5125);
DISPLAY INVISIBLE (-6275 5125);
FORCEPROP 1 LAST HDL_TAP TRUE
J 0
(-5950 4950);
DISPLAY 0.872340 (-5950 4950);
DISPLAY INVISIBLE (-5950 4950);
FORCEPROP 1 LAST PATH I274
J 0
(-6277 5075);
DISPLAY 0.872340 (-6277 5075);
PAINT GREEN (-6277 5075);
DISPLAY INVISIBLE (-6277 5075);
FORCEADD TAP..1
(-6275 5125);
FORCEPROP 3 LASTPIN (-6325 5125) SIG_NAME M_E_CPU0_SA_DQ<22>
J 0
(-6315 5135);
DISPLAY 0.659574 (-6315 5135);
PAINT MONO (-6315 5135);
DISPLAY INVISIBLE (-6315 5135);
FORCEPROP 1 LASTPIN (-6325 5125) BN 22
J 0
(-6337 5133);
DISPLAY 0.489362 (-6337 5133);
PAINT GREEN (-6337 5133);
FORCEPROP 2 LAST CDS_LIB mstr_standard
J 0
(-6275 5125);
DISPLAY 0.723404 (-6275 5125);
PAINT MONO (-6275 5125);
DISPLAY INVISIBLE (-6275 5125);
FORCEPROP 1 LAST BODY_TYPE PLUMBING
J 0
(-6275 5175);
DISPLAY 0.872340 (-6275 5175);
PAINT GREEN (-6275 5175);
DISPLAY INVISIBLE (-6275 5175);
FORCEPROP 1 LAST HDL_TAP TRUE
J 0
(-5950 5000);
DISPLAY 0.872340 (-5950 5000);
DISPLAY INVISIBLE (-5950 5000);
FORCEPROP 1 LAST PATH I275
J 0
(-6277 5125);
DISPLAY 0.872340 (-6277 5125);
PAINT GREEN (-6277 5125);
DISPLAY INVISIBLE (-6277 5125);
FORCEADD TAP..1
(-6275 5225);
FORCEPROP 3 LASTPIN (-6325 5225) SIG_NAME M_E_CPU0_SA_DQ<24>
J 0
(-6315 5235);
DISPLAY 0.659574 (-6315 5235);
PAINT MONO (-6315 5235);
DISPLAY INVISIBLE (-6315 5235);
FORCEPROP 1 LASTPIN (-6325 5225) BN 24
J 0
(-6337 5233);
DISPLAY 0.489362 (-6337 5233);
PAINT GREEN (-6337 5233);
FORCEPROP 2 LAST CDS_LIB mstr_standard
J 0
(-6275 5225);
DISPLAY 0.723404 (-6275 5225);
PAINT MONO (-6275 5225);
DISPLAY INVISIBLE (-6275 5225);
FORCEPROP 1 LAST BODY_TYPE PLUMBING
J 0
(-6275 5275);
DISPLAY 0.872340 (-6275 5275);
PAINT GREEN (-6275 5275);
DISPLAY INVISIBLE (-6275 5275);
FORCEPROP 1 LAST HDL_TAP TRUE
J 0
(-5950 5100);
DISPLAY 0.872340 (-5950 5100);
DISPLAY INVISIBLE (-5950 5100);
FORCEPROP 1 LAST PATH I276
J 0
(-6277 5225);
DISPLAY 0.872340 (-6277 5225);
PAINT GREEN (-6277 5225);
DISPLAY INVISIBLE (-6277 5225);
FORCEADD TAP..1
(-6275 5275);
FORCEPROP 3 LASTPIN (-6325 5275) SIG_NAME M_E_CPU0_SA_DQ<25>
J 0
(-6315 5285);
DISPLAY 0.659574 (-6315 5285);
PAINT MONO (-6315 5285);
DISPLAY INVISIBLE (-6315 5285);
FORCEPROP 1 LASTPIN (-6325 5275) BN 25
J 0
(-6337 5283);
DISPLAY 0.489362 (-6337 5283);
PAINT GREEN (-6337 5283);
FORCEPROP 2 LAST CDS_LIB mstr_standard
J 0
(-6275 5275);
DISPLAY 0.723404 (-6275 5275);
PAINT MONO (-6275 5275);
DISPLAY INVISIBLE (-6275 5275);
FORCEPROP 1 LAST BODY_TYPE PLUMBING
J 0
(-6275 5325);
DISPLAY 0.872340 (-6275 5325);
PAINT GREEN (-6275 5325);
DISPLAY INVISIBLE (-6275 5325);
FORCEPROP 1 LAST HDL_TAP TRUE
J 0
(-5950 5150);
DISPLAY 0.872340 (-5950 5150);
DISPLAY INVISIBLE (-5950 5150);
FORCEPROP 1 LAST PATH I277
J 0
(-6277 5275);
DISPLAY 0.872340 (-6277 5275);
PAINT GREEN (-6277 5275);
DISPLAY INVISIBLE (-6277 5275);
FORCEADD TAP..1
(-6275 5325);
FORCEPROP 3 LASTPIN (-6325 5325) SIG_NAME M_E_CPU0_SA_DQ<26>
J 0
(-6315 5335);
DISPLAY 0.659574 (-6315 5335);
PAINT MONO (-6315 5335);
DISPLAY INVISIBLE (-6315 5335);
FORCEPROP 1 LASTPIN (-6325 5325) BN 26
J 0
(-6337 5333);
DISPLAY 0.489362 (-6337 5333);
PAINT GREEN (-6337 5333);
FORCEPROP 2 LAST CDS_LIB mstr_standard
J 0
(-6275 5325);
DISPLAY 0.723404 (-6275 5325);
PAINT MONO (-6275 5325);
DISPLAY INVISIBLE (-6275 5325);
FORCEPROP 1 LAST BODY_TYPE PLUMBING
J 0
(-6275 5375);
DISPLAY 0.872340 (-6275 5375);
PAINT GREEN (-6275 5375);
DISPLAY INVISIBLE (-6275 5375);
FORCEPROP 1 LAST HDL_TAP TRUE
J 0
(-5950 5200);
DISPLAY 0.872340 (-5950 5200);
DISPLAY INVISIBLE (-5950 5200);
FORCEPROP 1 LAST PATH I278
J 0
(-6277 5325);
DISPLAY 0.872340 (-6277 5325);
PAINT GREEN (-6277 5325);
DISPLAY INVISIBLE (-6277 5325);
FORCEADD TAP..1
(-6275 5575);
FORCEPROP 3 LASTPIN (-6325 5575) SIG_NAME M_E_CPU0_SA_DQ<31>
J 0
(-6315 5585);
DISPLAY 0.659574 (-6315 5585);
PAINT MONO (-6315 5585);
DISPLAY INVISIBLE (-6315 5585);
FORCEPROP 1 LASTPIN (-6325 5575) BN 31
J 0
(-6337 5583);
DISPLAY 0.489362 (-6337 5583);
PAINT GREEN (-6337 5583);
FORCEPROP 2 LAST CDS_LIB mstr_standard
J 0
(-6275 5575);
DISPLAY 0.723404 (-6275 5575);
PAINT MONO (-6275 5575);
DISPLAY INVISIBLE (-6275 5575);
FORCEPROP 1 LAST BODY_TYPE PLUMBING
J 0
(-6275 5625);
DISPLAY 0.872340 (-6275 5625);
PAINT GREEN (-6275 5625);
DISPLAY INVISIBLE (-6275 5625);
FORCEPROP 1 LAST HDL_TAP TRUE
J 0
(-5950 5450);
DISPLAY 0.872340 (-5950 5450);
DISPLAY INVISIBLE (-5950 5450);
FORCEPROP 1 LAST PATH I279
J 0
(-6277 5575);
DISPLAY 0.872340 (-6277 5575);
PAINT GREEN (-6277 5575);
DISPLAY INVISIBLE (-6277 5575);
FORCEADD TAP..1
(-6275 5375);
FORCEPROP 3 LASTPIN (-6325 5375) SIG_NAME M_E_CPU0_SA_DQ<27>
J 0
(-6315 5385);
DISPLAY 0.659574 (-6315 5385);
PAINT MONO (-6315 5385);
DISPLAY INVISIBLE (-6315 5385);
FORCEPROP 1 LASTPIN (-6325 5375) BN 27
J 0
(-6337 5383);
DISPLAY 0.489362 (-6337 5383);
PAINT GREEN (-6337 5383);
FORCEPROP 2 LAST CDS_LIB mstr_standard
J 0
(-6275 5375);
DISPLAY 0.723404 (-6275 5375);
PAINT MONO (-6275 5375);
DISPLAY INVISIBLE (-6275 5375);
FORCEPROP 1 LAST BODY_TYPE PLUMBING
J 0
(-6275 5425);
DISPLAY 0.872340 (-6275 5425);
PAINT GREEN (-6275 5425);
DISPLAY INVISIBLE (-6275 5425);
FORCEPROP 1 LAST HDL_TAP TRUE
J 0
(-5950 5250);
DISPLAY 0.872340 (-5950 5250);
DISPLAY INVISIBLE (-5950 5250);
FORCEPROP 1 LAST PATH I280
J 0
(-6277 5375);
DISPLAY 0.872340 (-6277 5375);
PAINT GREEN (-6277 5375);
DISPLAY INVISIBLE (-6277 5375);
FORCEADD TAP..1
(-6275 5425);
FORCEPROP 3 LASTPIN (-6325 5425) SIG_NAME M_E_CPU0_SA_DQ<28>
J 0
(-6315 5435);
DISPLAY 0.659574 (-6315 5435);
PAINT MONO (-6315 5435);
DISPLAY INVISIBLE (-6315 5435);
FORCEPROP 1 LASTPIN (-6325 5425) BN 28
J 0
(-6337 5433);
DISPLAY 0.489362 (-6337 5433);
PAINT GREEN (-6337 5433);
FORCEPROP 2 LAST CDS_LIB mstr_standard
J 0
(-6275 5425);
DISPLAY 0.723404 (-6275 5425);
PAINT MONO (-6275 5425);
DISPLAY INVISIBLE (-6275 5425);
FORCEPROP 1 LAST BODY_TYPE PLUMBING
J 0
(-6275 5475);
DISPLAY 0.872340 (-6275 5475);
PAINT GREEN (-6275 5475);
DISPLAY INVISIBLE (-6275 5475);
FORCEPROP 1 LAST HDL_TAP TRUE
J 0
(-5950 5300);
DISPLAY 0.872340 (-5950 5300);
DISPLAY INVISIBLE (-5950 5300);
FORCEPROP 1 LAST PATH I281
J 0
(-6277 5425);
DISPLAY 0.872340 (-6277 5425);
PAINT GREEN (-6277 5425);
DISPLAY INVISIBLE (-6277 5425);
FORCEADD TAP..1
(-6275 5525);
FORCEPROP 3 LASTPIN (-6325 5525) SIG_NAME M_E_CPU0_SA_DQ<30>
J 0
(-6315 5535);
DISPLAY 0.659574 (-6315 5535);
PAINT MONO (-6315 5535);
DISPLAY INVISIBLE (-6315 5535);
FORCEPROP 1 LASTPIN (-6325 5525) BN 30
J 0
(-6337 5533);
DISPLAY 0.489362 (-6337 5533);
PAINT GREEN (-6337 5533);
FORCEPROP 2 LAST CDS_LIB mstr_standard
J 0
(-6275 5525);
DISPLAY 0.723404 (-6275 5525);
PAINT MONO (-6275 5525);
DISPLAY INVISIBLE (-6275 5525);
FORCEPROP 1 LAST BODY_TYPE PLUMBING
J 0
(-6275 5575);
DISPLAY 0.872340 (-6275 5575);
PAINT GREEN (-6275 5575);
DISPLAY INVISIBLE (-6275 5575);
FORCEPROP 1 LAST HDL_TAP TRUE
J 0
(-5950 5400);
DISPLAY 0.872340 (-5950 5400);
DISPLAY INVISIBLE (-5950 5400);
FORCEPROP 1 LAST PATH I282
J 0
(-6277 5525);
DISPLAY 0.872340 (-6277 5525);
PAINT GREEN (-6277 5525);
DISPLAY INVISIBLE (-6277 5525);
FORCEADD TAP..1
(-6275 5475);
FORCEPROP 3 LASTPIN (-6325 5475) SIG_NAME M_E_CPU0_SA_DQ<29>
J 0
(-6315 5485);
DISPLAY 0.659574 (-6315 5485);
PAINT MONO (-6315 5485);
DISPLAY INVISIBLE (-6315 5485);
FORCEPROP 1 LASTPIN (-6325 5475) BN 29
J 0
(-6337 5483);
DISPLAY 0.489362 (-6337 5483);
PAINT GREEN (-6337 5483);
FORCEPROP 2 LAST CDS_LIB mstr_standard
J 0
(-6275 5475);
DISPLAY 0.723404 (-6275 5475);
PAINT MONO (-6275 5475);
DISPLAY INVISIBLE (-6275 5475);
FORCEPROP 1 LAST BODY_TYPE PLUMBING
J 0
(-6275 5525);
DISPLAY 0.872340 (-6275 5525);
PAINT GREEN (-6275 5525);
DISPLAY INVISIBLE (-6275 5525);
FORCEPROP 1 LAST HDL_TAP TRUE
J 0
(-5950 5350);
DISPLAY 0.872340 (-5950 5350);
DISPLAY INVISIBLE (-5950 5350);
FORCEPROP 1 LAST PATH I283
J 0
(-6277 5475);
DISPLAY 0.872340 (-6277 5475);
PAINT GREEN (-6277 5475);
DISPLAY INVISIBLE (-6277 5475);
FORCEADD OFFPAGE..3
(-5625 5650);
FORCEPROP 2 LAST $XR0 14 
J 0
(-5411 5650);
DISPLAY 0.638298 (-5411 5650);
PAINT MONO (-5411 5650);
FORCEPROP 2 LAST PATH I284
J 0
(-5400 5700);
DISPLAY 0.808511 (-5400 5700);
DISPLAY INVISIBLE (-5400 5700);
FORCEPROP 1 LAST COMMENT_BODY TRUE
J 0
(-5675 5550);
DISPLAY 0.872340 (-5675 5550);
PAINT GREEN (-5675 5550);
DISPLAY INVISIBLE (-5675 5550);
FORCEPROP 1 LAST OFFPAGE TRUE
J 0
(-5300 5525);
DISPLAY 0.872340 (-5300 5525);
PAINT GREEN (-5300 5525);
DISPLAY INVISIBLE (-5300 5525);
FORCEPROP 2 LAST CDS_LIB mstr_standard
J 0
(-5625 5650);
DISPLAY 0.723404 (-5625 5650);
PAINT MONO (-5625 5650);
DISPLAY INVISIBLE (-5625 5650);
FORCEADD Q_RES..2
(-6650 1425);
FORCEPROP 1 LAST LOCATION R5
J 0
(-6605 1550);
DISPLAY 0.489362 (-6605 1550);
PAINT SKYBLUE (-6605 1550);
FORCEPROP 2 LAST SEC 1
J 0
(-6600 1650);
DISPLAY 0.808511 (-6600 1650);
PAINT MONO (-6600 1650);
DISPLAY INVISIBLE (-6600 1650);
FORCEPROP 1 LASTPIN (-6650 1525) $PN 1
J 0
(-6645 1487);
DISPLAY 0.489362 (-6645 1487);
PAINT WHITE (-6645 1487);
FORCEPROP 1 LASTPIN (-6650 1325) $PN 2
J 0
(-6645 1335);
DISPLAY 0.489362 (-6645 1335);
PAINT WHITE (-6645 1335);
FORCEPROP 0 LASTPIN (-6650 1525) XNET_PINS 3
R 1
J 0
(-6660 1535);
DISPLAY 0.808511 (-6660 1535);
PAINT MONO (-6660 1535);
DISPLAY INVISIBLE (-6660 1535);
FORCEPROP 0 LASTPIN (-6650 1325) XNET_PINS 2
R 1
J 2
(-6660 1315);
DISPLAY 0.808511 (-6660 1315);
PAINT MONO (-6660 1315);
DISPLAY INVISIBLE (-6660 1315);
FORCEPROP 1 LAST WATTAGE 1/16W
J 0
(-6610 1400);
DISPLAY 0.489362 (-6610 1400);
PAINT SKYBLUE (-6610 1400);
FORCEPROP 1 LAST MATERIAL CHIP
J 0
(-6610 1350);
DISPLAY 0.489362 (-6610 1350);
PAINT SKYBLUE (-6610 1350);
FORCEPROP 1 LAST TOLERANCE 1%
J 0
(-6605 1450);
DISPLAY 0.489362 (-6605 1450);
PAINT SKYBLUE (-6605 1450);
FORCEPROP 1 LAST VALUE 54.9K
J 0
(-6605 1500);
DISPLAY 0.489362 (-6605 1500);
PAINT SKYBLUE (-6605 1500);
FORCEPROP 1 LAST PART_NUMBER TMP_QCS35492FB14
J 0
(-6610 1300);
DISPLAY 0.489362 (-6610 1300);
PAINT SKYBLUE (-6610 1300);
FORCEPROP 1 LAST PACK_TYPE 0402LF
J 0
(-6610 1250);
DISPLAY 0.489362 (-6610 1250);
PAINT SKYBLUE (-6610 1250);
FORCEPROP 2 LAST BOM_COST MEM
J 0
(-6600 1600);
DISPLAY 0.808511 (-6600 1600);
DISPLAY INVISIBLE (-6600 1600);
FORCEPROP 2 LAST CDS_LIB pure_quanta
J 0
(-6650 1425);
DISPLAY INVISIBLE (-6650 1425);
FORCEPROP 2 LAST SEC_TYPE 0402LF
J 0
(-6600 1650);
DISPLAY 0.808511 (-6600 1650);
PAINT MONO (-6600 1650);
DISPLAY INVISIBLE (-6600 1650);
FORCEPROP 1 LAST PATH I331
J 0
(-6600 1600);
DISPLAY 0.978723 (-6600 1600);
PAINT WHITE (-6600 1600);
DISPLAY INVISIBLE (-6600 1600);
FORCEADD GND..1
(-6650 1200);
FORCEPROP 3 LASTPIN (-6650 1250) SIG_NAME GND\g
J 0
(-6640 1260);
DISPLAY 0.659574 (-6640 1260);
PAINT MONO (-6640 1260);
DISPLAY INVISIBLE (-6640 1260);
FORCEPROP 1 LAST SIZE 1B
J 0
(-6575 1150);
DISPLAY 0.851064 (-6575 1150);
PAINT GREEN (-6575 1150);
DISPLAY INVISIBLE (-6575 1150);
FORCEPROP 2 LAST CDS_LIB mstr_symbols
J 0
(-6650 1200);
DISPLAY 0.808511 (-6650 1200);
DISPLAY INVISIBLE (-6650 1200);
FORCEPROP 2 LAST BOM_COST MEM
J 0
(-6750 1275);
DISPLAY 0.808511 (-6750 1275);
DISPLAY INVISIBLE (-6750 1275);
FORCEPROP 1 LAST BODY_TYPE PLUMBING
J 0
(-6695 1157);
DISPLAY 0.340426 (-6695 1157);
PAINT GREEN (-6695 1157);
DISPLAY INVISIBLE (-6695 1157);
FORCEPROP 1 LAST PATH I332
J 0
(-6575 1200);
DISPLAY 0.872340 (-6575 1200);
PAINT GREEN (-6575 1200);
DISPLAY INVISIBLE (-6575 1200);
FORCEPROP 1 LAST VOLTAGE 0.0
J 0
(-6695 1157);
DISPLAY 0.723404 (-6695 1157);
PAINT SKYBLUE (-6695 1157);
DISPLAY INVISIBLE (-6695 1157);
FORCEPROP 1 LAST HDL_POWER GND
J 0
(-6650 1350);
DISPLAY 0.851064 (-6650 1350);
PAINT GREEN (-6650 1350);
DISPLAY INVISIBLE (-6650 1350);
FORCEADD OFFPAGE..5
(-7425 1600);
FORCEPROP 2 LAST $XR0 89 
J 0
(-7649 1600);
DISPLAY 0.638298 (-7649 1600);
PAINT MONO (-7649 1600);
FORCEPROP 2 LAST PATH I333
J 0
(-7375 1675);
DISPLAY 0.808511 (-7375 1675);
DISPLAY INVISIBLE (-7375 1675);
FORCEPROP 1 LAST COMMENT_BODY TRUE
J 0
(-7325 1525);
DISPLAY 0.872340 (-7325 1525);
PAINT GREEN (-7325 1525);
DISPLAY INVISIBLE (-7325 1525);
FORCEPROP 1 LAST OFFPAGE TRUE
J 0
(-7100 1475);
DISPLAY 0.872340 (-7100 1475);
PAINT GREEN (-7100 1475);
DISPLAY INVISIBLE (-7100 1475);
FORCEPROP 2 LAST CDS_LIB mstr_standard
J 0
(-7425 1600);
DISPLAY 0.808511 (-7425 1600);
DISPLAY INVISIBLE (-7425 1600);
FORCEPROP 2 LAST BOM_COST MEM
J 0
(-7500 1675);
DISPLAY 0.808511 (-7500 1675);
DISPLAY INVISIBLE (-7500 1675);
FORCEADD OFFPAGE..1
(-8575 3075);
FORCEPROP 2 LAST $XR0 89 
J 0
(-8826 3075);
DISPLAY 0.638298 (-8826 3075);
PAINT MONO (-8826 3075);
FORCEPROP 2 LAST PATH I334
J 0
(-8525 3150);
DISPLAY 0.808511 (-8525 3150);
DISPLAY INVISIBLE (-8525 3150);
FORCEPROP 1 LAST COMMENT_BODY TRUE
J 0
(-8450 2975);
DISPLAY 0.872340 (-8450 2975);
PAINT GREEN (-8450 2975);
DISPLAY INVISIBLE (-8450 2975);
FORCEPROP 1 LAST OFFPAGE TRUE
J 0
(-8250 2950);
DISPLAY 0.872340 (-8250 2950);
PAINT GREEN (-8250 2950);
DISPLAY INVISIBLE (-8250 2950);
FORCEPROP 2 LAST CDS_LIB mstr_standard
J 0
(-8575 3075);
DISPLAY 0.808511 (-8575 3075);
DISPLAY INVISIBLE (-8575 3075);
FORCEADD SCONN288_DDR506112002KQ..1
(-7125 3825);
FORCEPROP 1 LAST LOCATION J21
J 0
(-7575 5900);
DISPLAY 0.468085 (-7575 5900);
PAINT SKYBLUE (-7575 5900);
FORCEPROP 0 LAST $SEC 1
J 0
(-7575 6050);
DISPLAY 0.680851 (-7575 6050);
PAINT MONO (-7575 6050);
DISPLAY INVISIBLE (-7575 6050);
FORCEPROP 2 LAST CDS_SEC 1
J 0
(-7575 6050);
DISPLAY 1.021277 (-7575 6050);
DISPLAY INVISIBLE (-7575 6050);
FORCEPROP 0 LASTPIN (-7725 3225) $PN 62
J 2
(-7735 3235);
DISPLAY 0.680851 (-7735 3235);
PAINT MONO (-7735 3235);
FORCEPROP 0 LASTPIN (-7725 5275) $PN 66
J 2
(-7735 5285);
DISPLAY 0.680851 (-7735 5285);
PAINT MONO (-7735 5285);
FORCEPROP 0 LASTPIN (-7725 4875) $PN 76
J 2
(-7735 4885);
DISPLAY 0.680851 (-7735 4885);
PAINT MONO (-7735 4885);
FORCEPROP 0 LASTPIN (-7725 5325) $PN 211
J 2
(-7735 5335);
DISPLAY 0.680851 (-7735 5335);
PAINT MONO (-7735 5335);
FORCEPROP 0 LASTPIN (-7725 4925) $PN 221
J 2
(-7735 4935);
DISPLAY 0.680851 (-7735 4935);
PAINT MONO (-7735 4935);
FORCEPROP 0 LASTPIN (-7725 5375) $PN 68
J 2
(-7735 5385);
DISPLAY 0.680851 (-7735 5385);
PAINT MONO (-7735 5385);
FORCEPROP 0 LASTPIN (-7725 4975) $PN 78
J 2
(-7735 4985);
DISPLAY 0.680851 (-7735 4985);
PAINT MONO (-7735 4985);
FORCEPROP 0 LASTPIN (-7725 5425) $PN 213
J 2
(-7735 5435);
DISPLAY 0.680851 (-7735 5435);
PAINT MONO (-7735 5435);
FORCEPROP 0 LASTPIN (-7725 5025) $PN 223
J 2
(-7735 5035);
DISPLAY 0.680851 (-7735 5035);
PAINT MONO (-7735 5035);
FORCEPROP 0 LASTPIN (-7725 5475) $PN 70
J 2
(-7735 5485);
DISPLAY 0.680851 (-7735 5485);
PAINT MONO (-7735 5485);
FORCEPROP 0 LASTPIN (-7725 5075) $PN 80
J 2
(-7735 5085);
DISPLAY 0.680851 (-7735 5085);
PAINT MONO (-7735 5085);
FORCEPROP 0 LASTPIN (-7725 5525) $PN 215
J 2
(-7735 5535);
DISPLAY 0.680851 (-7735 5535);
PAINT MONO (-7735 5535);
FORCEPROP 0 LASTPIN (-7725 5125) $PN 225
J 2
(-7735 5135);
DISPLAY 0.680851 (-7735 5135);
PAINT MONO (-7735 5135);
FORCEPROP 0 LASTPIN (-7725 5575) $PN 72
J 2
(-7735 5585);
DISPLAY 0.680851 (-7735 5585);
PAINT MONO (-7735 5585);
FORCEPROP 0 LASTPIN (-7725 5175) $PN 82
J 2
(-7735 5185);
DISPLAY 0.680851 (-7735 5185);
PAINT MONO (-7735 5185);
FORCEPROP 0 LASTPIN (-7725 3825) $PN 51
J 2
(-7735 3835);
DISPLAY 0.680851 (-7735 3835);
PAINT MONO (-7735 3835);
FORCEPROP 0 LASTPIN (-7725 3375) $PN 96
J 2
(-7735 3385);
DISPLAY 0.680851 (-7735 3385);
PAINT MONO (-7735 3385);
FORCEPROP 0 LASTPIN (-7725 3875) $PN 53
J 2
(-7735 3885);
DISPLAY 0.680851 (-7735 3885);
PAINT MONO (-7735 3885);
FORCEPROP 0 LASTPIN (-7725 3425) $PN 98
J 2
(-7735 3435);
DISPLAY 0.680851 (-7735 3435);
PAINT MONO (-7735 3435);
FORCEPROP 0 LASTPIN (-7725 3925) $PN 196
J 2
(-7735 3935);
DISPLAY 0.680851 (-7735 3935);
PAINT MONO (-7735 3935);
FORCEPROP 0 LASTPIN (-7725 3475) $PN 241
J 2
(-7735 3485);
DISPLAY 0.680851 (-7735 3485);
PAINT MONO (-7735 3485);
FORCEPROP 0 LASTPIN (-7725 3975) $PN 198
J 2
(-7735 3985);
DISPLAY 0.680851 (-7735 3985);
PAINT MONO (-7735 3985);
FORCEPROP 0 LASTPIN (-7725 3525) $PN 243
J 2
(-7735 3535);
DISPLAY 0.680851 (-7735 3535);
PAINT MONO (-7735 3535);
FORCEPROP 0 LASTPIN (-7725 4025) $PN 58
J 2
(-7735 4035);
DISPLAY 0.680851 (-7735 4035);
PAINT MONO (-7735 4035);
FORCEPROP 0 LASTPIN (-7725 3575) $PN 89
J 2
(-7735 3585);
DISPLAY 0.680851 (-7735 3585);
PAINT MONO (-7735 3585);
FORCEPROP 0 LASTPIN (-7725 4075) $PN 60
J 2
(-7735 4085);
DISPLAY 0.680851 (-7735 4085);
PAINT MONO (-7735 4085);
FORCEPROP 0 LASTPIN (-7725 3625) $PN 91
J 2
(-7735 3635);
DISPLAY 0.680851 (-7735 3635);
PAINT MONO (-7735 3635);
FORCEPROP 0 LASTPIN (-7725 4125) $PN 203
J 2
(-7735 4135);
DISPLAY 0.680851 (-7735 4135);
PAINT MONO (-7735 4135);
FORCEPROP 0 LASTPIN (-7725 3675) $PN 234
J 2
(-7735 3685);
DISPLAY 0.680851 (-7735 3685);
PAINT MONO (-7735 3685);
FORCEPROP 0 LASTPIN (-7725 4175) $PN 205
J 2
(-7735 4185);
DISPLAY 0.680851 (-7735 4185);
PAINT MONO (-7735 4185);
FORCEPROP 0 LASTPIN (-7725 3725) $PN 236
J 2
(-7735 3735);
DISPLAY 0.680851 (-7735 3735);
PAINT MONO (-7735 3735);
FORCEPROP 0 LASTPIN (-7725 4275) $PN 218
J 2
(-7735 4285);
DISPLAY 0.680851 (-7735 4285);
PAINT MONO (-7735 4285);
FORCEPROP 0 LASTPIN (-7725 4325) $PN 217
J 2
(-7735 4335);
DISPLAY 0.680851 (-7735 4335);
PAINT MONO (-7735 4335);
FORCEPROP 0 LASTPIN (-7725 4575) $PN 64
J 2
(-7735 4585);
DISPLAY 0.680851 (-7735 4585);
PAINT MONO (-7735 4585);
FORCEPROP 0 LASTPIN (-7725 4425) $PN 84
J 2
(-7735 4435);
DISPLAY 0.680851 (-7735 4435);
PAINT MONO (-7735 4435);
FORCEPROP 0 LASTPIN (-7725 4625) $PN 209
J 2
(-7735 4635);
DISPLAY 0.680851 (-7735 4635);
PAINT MONO (-7735 4635);
FORCEPROP 0 LASTPIN (-7725 4475) $PN 229
J 2
(-7735 4485);
DISPLAY 0.680851 (-7735 4485);
PAINT MONO (-7735 4485);
FORCEPROP 0 LASTPIN (-6525 4025) $PN 7
J 0
(-6515 4035);
DISPLAY 0.680851 (-6515 4035);
PAINT MONO (-6515 4035);
FORCEPROP 0 LASTPIN (-6525 2375) $PN 100
J 0
(-6515 2385);
DISPLAY 0.680851 (-6515 2385);
PAINT MONO (-6515 2385);
FORCEPROP 0 LASTPIN (-6525 4075) $PN 9
J 0
(-6515 4085);
DISPLAY 0.680851 (-6515 4085);
PAINT MONO (-6515 4085);
FORCEPROP 0 LASTPIN (-6525 2425) $PN 102
J 0
(-6515 2435);
DISPLAY 0.680851 (-6515 2435);
PAINT MONO (-6515 2435);
FORCEPROP 0 LASTPIN (-6525 4125) $PN 152
J 0
(-6515 4135);
DISPLAY 0.680851 (-6515 4135);
PAINT MONO (-6515 4135);
FORCEPROP 0 LASTPIN (-6525 2475) $PN 245
J 0
(-6515 2485);
DISPLAY 0.680851 (-6515 2485);
PAINT MONO (-6515 2485);
FORCEPROP 0 LASTPIN (-6525 4175) $PN 154
J 0
(-6515 4185);
DISPLAY 0.680851 (-6515 4185);
PAINT MONO (-6515 4185);
FORCEPROP 0 LASTPIN (-6525 2525) $PN 247
J 0
(-6515 2535);
DISPLAY 0.680851 (-6515 2535);
PAINT MONO (-6515 2535);
FORCEPROP 0 LASTPIN (-6525 4225) $PN 14
J 0
(-6515 4235);
DISPLAY 0.680851 (-6515 4235);
PAINT MONO (-6515 4235);
FORCEPROP 0 LASTPIN (-6525 2575) $PN 107
J 0
(-6515 2585);
DISPLAY 0.680851 (-6515 2585);
PAINT MONO (-6515 2585);
FORCEPROP 0 LASTPIN (-6525 4275) $PN 16
J 0
(-6515 4285);
DISPLAY 0.680851 (-6515 4285);
PAINT MONO (-6515 4285);
FORCEPROP 0 LASTPIN (-6525 2625) $PN 109
J 0
(-6515 2635);
DISPLAY 0.680851 (-6515 2635);
PAINT MONO (-6515 2635);
FORCEPROP 0 LASTPIN (-6525 4325) $PN 159
J 0
(-6515 4335);
DISPLAY 0.680851 (-6515 4335);
PAINT MONO (-6515 4335);
FORCEPROP 0 LASTPIN (-6525 2675) $PN 252
J 0
(-6515 2685);
DISPLAY 0.680851 (-6515 2685);
PAINT MONO (-6515 2685);
FORCEPROP 0 LASTPIN (-6525 4375) $PN 161
J 0
(-6515 4385);
DISPLAY 0.680851 (-6515 4385);
PAINT MONO (-6515 4385);
FORCEPROP 0 LASTPIN (-6525 2725) $PN 254
J 0
(-6515 2735);
DISPLAY 0.680851 (-6515 2735);
PAINT MONO (-6515 2735);
FORCEPROP 0 LASTPIN (-6525 4425) $PN 18
J 0
(-6515 4435);
DISPLAY 0.680851 (-6515 4435);
PAINT MONO (-6515 4435);
FORCEPROP 0 LASTPIN (-6525 2775) $PN 111
J 0
(-6515 2785);
DISPLAY 0.680851 (-6515 2785);
PAINT MONO (-6515 2785);
FORCEPROP 0 LASTPIN (-6525 4475) $PN 20
J 0
(-6515 4485);
DISPLAY 0.680851 (-6515 4485);
PAINT MONO (-6515 4485);
FORCEPROP 0 LASTPIN (-6525 2825) $PN 113
J 0
(-6515 2835);
DISPLAY 0.680851 (-6515 2835);
PAINT MONO (-6515 2835);
FORCEPROP 0 LASTPIN (-6525 4525) $PN 163
J 0
(-6515 4535);
DISPLAY 0.680851 (-6515 4535);
PAINT MONO (-6515 4535);
FORCEPROP 0 LASTPIN (-6525 2875) $PN 256
J 0
(-6515 2885);
DISPLAY 0.680851 (-6515 2885);
PAINT MONO (-6515 2885);
FORCEPROP 0 LASTPIN (-6525 4575) $PN 165
J 0
(-6515 4585);
DISPLAY 0.680851 (-6515 4585);
PAINT MONO (-6515 4585);
FORCEPROP 0 LASTPIN (-6525 2925) $PN 258
J 0
(-6515 2935);
DISPLAY 0.680851 (-6515 2935);
PAINT MONO (-6515 2935);
FORCEPROP 0 LASTPIN (-6525 4625) $PN 25
J 0
(-6515 4635);
DISPLAY 0.680851 (-6515 4635);
PAINT MONO (-6515 4635);
FORCEPROP 0 LASTPIN (-6525 2975) $PN 118
J 0
(-6515 2985);
DISPLAY 0.680851 (-6515 2985);
PAINT MONO (-6515 2985);
FORCEPROP 0 LASTPIN (-6525 4675) $PN 27
J 0
(-6515 4685);
DISPLAY 0.680851 (-6515 4685);
PAINT MONO (-6515 4685);
FORCEPROP 0 LASTPIN (-6525 3025) $PN 120
J 0
(-6515 3035);
DISPLAY 0.680851 (-6515 3035);
PAINT MONO (-6515 3035);
FORCEPROP 0 LASTPIN (-6525 4725) $PN 170
J 0
(-6515 4735);
DISPLAY 0.680851 (-6515 4735);
PAINT MONO (-6515 4735);
FORCEPROP 0 LASTPIN (-6525 3075) $PN 263
J 0
(-6515 3085);
DISPLAY 0.680851 (-6515 3085);
PAINT MONO (-6515 3085);
FORCEPROP 0 LASTPIN (-6525 4775) $PN 172
J 0
(-6515 4785);
DISPLAY 0.680851 (-6515 4785);
PAINT MONO (-6515 4785);
FORCEPROP 0 LASTPIN (-6525 3125) $PN 265
J 0
(-6515 3135);
DISPLAY 0.680851 (-6515 3135);
PAINT MONO (-6515 3135);
FORCEPROP 0 LASTPIN (-6525 4825) $PN 29
J 0
(-6515 4835);
DISPLAY 0.680851 (-6515 4835);
PAINT MONO (-6515 4835);
FORCEPROP 0 LASTPIN (-6525 3175) $PN 122
J 0
(-6515 3185);
DISPLAY 0.680851 (-6515 3185);
PAINT MONO (-6515 3185);
FORCEPROP 0 LASTPIN (-6525 4875) $PN 31
J 0
(-6515 4885);
DISPLAY 0.680851 (-6515 4885);
PAINT MONO (-6515 4885);
FORCEPROP 0 LASTPIN (-6525 3225) $PN 124
J 0
(-6515 3235);
DISPLAY 0.680851 (-6515 3235);
PAINT MONO (-6515 3235);
FORCEPROP 0 LASTPIN (-6525 4925) $PN 174
J 0
(-6515 4935);
DISPLAY 0.680851 (-6515 4935);
PAINT MONO (-6515 4935);
FORCEPROP 0 LASTPIN (-6525 3275) $PN 267
J 0
(-6515 3285);
DISPLAY 0.680851 (-6515 3285);
PAINT MONO (-6515 3285);
FORCEPROP 0 LASTPIN (-6525 4975) $PN 176
J 0
(-6515 4985);
DISPLAY 0.680851 (-6515 4985);
PAINT MONO (-6515 4985);
FORCEPROP 0 LASTPIN (-6525 3325) $PN 269
J 0
(-6515 3335);
DISPLAY 0.680851 (-6515 3335);
PAINT MONO (-6515 3335);
FORCEPROP 0 LASTPIN (-6525 5025) $PN 36
J 0
(-6515 5035);
DISPLAY 0.680851 (-6515 5035);
PAINT MONO (-6515 5035);
FORCEPROP 0 LASTPIN (-6525 3375) $PN 129
J 0
(-6515 3385);
DISPLAY 0.680851 (-6515 3385);
PAINT MONO (-6515 3385);
FORCEPROP 0 LASTPIN (-6525 5075) $PN 38
J 0
(-6515 5085);
DISPLAY 0.680851 (-6515 5085);
PAINT MONO (-6515 5085);
FORCEPROP 0 LASTPIN (-6525 3425) $PN 131
J 0
(-6515 3435);
DISPLAY 0.680851 (-6515 3435);
PAINT MONO (-6515 3435);
FORCEPROP 0 LASTPIN (-6525 5125) $PN 181
J 0
(-6515 5135);
DISPLAY 0.680851 (-6515 5135);
PAINT MONO (-6515 5135);
FORCEPROP 0 LASTPIN (-6525 3475) $PN 274
J 0
(-6515 3485);
DISPLAY 0.680851 (-6515 3485);
PAINT MONO (-6515 3485);
FORCEPROP 0 LASTPIN (-6525 5175) $PN 183
J 0
(-6515 5185);
DISPLAY 0.680851 (-6515 5185);
PAINT MONO (-6515 5185);
FORCEPROP 0 LASTPIN (-6525 3525) $PN 276
J 0
(-6515 3535);
DISPLAY 0.680851 (-6515 3535);
PAINT MONO (-6515 3535);
FORCEPROP 0 LASTPIN (-6525 5225) $PN 40
J 0
(-6515 5235);
DISPLAY 0.680851 (-6515 5235);
PAINT MONO (-6515 5235);
FORCEPROP 0 LASTPIN (-6525 3575) $PN 133
J 0
(-6515 3585);
DISPLAY 0.680851 (-6515 3585);
PAINT MONO (-6515 3585);
FORCEPROP 0 LASTPIN (-6525 5275) $PN 42
J 0
(-6515 5285);
DISPLAY 0.680851 (-6515 5285);
PAINT MONO (-6515 5285);
FORCEPROP 0 LASTPIN (-6525 3625) $PN 135
J 0
(-6515 3635);
DISPLAY 0.680851 (-6515 3635);
PAINT MONO (-6515 3635);
FORCEPROP 0 LASTPIN (-6525 5325) $PN 185
J 0
(-6515 5335);
DISPLAY 0.680851 (-6515 5335);
PAINT MONO (-6515 5335);
FORCEPROP 0 LASTPIN (-6525 3675) $PN 278
J 0
(-6515 3685);
DISPLAY 0.680851 (-6515 3685);
PAINT MONO (-6515 3685);
FORCEPROP 0 LASTPIN (-6525 5375) $PN 187
J 0
(-6515 5385);
DISPLAY 0.680851 (-6515 5385);
PAINT MONO (-6515 5385);
FORCEPROP 0 LASTPIN (-6525 3725) $PN 280
J 0
(-6515 3735);
DISPLAY 0.680851 (-6515 3735);
PAINT MONO (-6515 3735);
FORCEPROP 0 LASTPIN (-6525 5425) $PN 47
J 0
(-6515 5435);
DISPLAY 0.680851 (-6515 5435);
PAINT MONO (-6515 5435);
FORCEPROP 0 LASTPIN (-6525 3775) $PN 140
J 0
(-6515 3785);
DISPLAY 0.680851 (-6515 3785);
PAINT MONO (-6515 3785);
FORCEPROP 0 LASTPIN (-6525 5475) $PN 49
J 0
(-6515 5485);
DISPLAY 0.680851 (-6515 5485);
PAINT MONO (-6515 5485);
FORCEPROP 0 LASTPIN (-6525 3825) $PN 142
J 0
(-6515 3835);
DISPLAY 0.680851 (-6515 3835);
PAINT MONO (-6515 3835);
FORCEPROP 0 LASTPIN (-6525 5525) $PN 192
J 0
(-6515 5535);
DISPLAY 0.680851 (-6515 5535);
PAINT MONO (-6515 5535);
FORCEPROP 0 LASTPIN (-6525 3875) $PN 285
J 0
(-6515 3885);
DISPLAY 0.680851 (-6515 3885);
PAINT MONO (-6515 3885);
FORCEPROP 0 LASTPIN (-6525 5575) $PN 194
J 0
(-6515 5585);
DISPLAY 0.680851 (-6515 5585);
PAINT MONO (-6515 5585);
FORCEPROP 0 LASTPIN (-6525 3925) $PN 287
J 0
(-6515 3935);
DISPLAY 0.680851 (-6515 3935);
PAINT MONO (-6515 3935);
FORCEPROP 0 LASTPIN (-7725 3075) $PN 148
J 2
(-7735 3085);
DISPLAY 0.680851 (-7735 3085);
PAINT MONO (-7735 3085);
FORCEPROP 0 LASTPIN (-7725 2975) $PN 4
J 2
(-7735 2985);
DISPLAY 0.680851 (-7735 2985);
PAINT MONO (-7735 2985);
FORCEPROP 0 LASTPIN (-7725 3025) $PN 5
J 2
(-7735 3035);
DISPLAY 0.680851 (-7735 3035);
PAINT MONO (-7735 3035);
FORCEPROP 0 LASTPIN (-7725 2175) $PN 86
J 2
(-7735 2185);
DISPLAY 0.680851 (-7735 2185);
PAINT MONO (-7735 2185);
FORCEPROP 0 LASTPIN (-7725 2125) $PN 87
J 2
(-7735 2135);
DISPLAY 0.680851 (-7735 2135);
PAINT MONO (-7735 2135);
FORCEPROP 0 LASTPIN (-7725 4775) $PN 74
J 2
(-7735 4785);
DISPLAY 0.680851 (-7735 4785);
PAINT MONO (-7735 4785);
FORCEPROP 0 LASTPIN (-7725 4725) $PN 227
J 2
(-7735 4735);
DISPLAY 0.680851 (-7735 4735);
PAINT MONO (-7735 4735);
FORCEPROP 0 LASTPIN (-7725 2725) $PN 147
J 2
(-7735 2735);
DISPLAY 0.680851 (-7735 2735);
PAINT MONO (-7735 2735);
FORCEPROP 0 LASTPIN (-7725 3275) $PN 207
J 2
(-7735 3285);
DISPLAY 0.680851 (-7735 3285);
PAINT MONO (-7735 3285);
FORCEPROP 0 LASTPIN (-7725 2325) $PN 2
J 2
(-7735 2335);
DISPLAY 0.680851 (-7735 2335);
PAINT MONO (-7735 2335);
FORCEPROP 0 LASTPIN (-7725 2375) $PN 144
J 2
(-7735 2385);
DISPLAY 0.680851 (-7735 2385);
PAINT MONO (-7735 2385);
FORCEPROP 0 LASTPIN (-7725 2425) $PN 149
J 2
(-7735 2435);
DISPLAY 0.680851 (-7735 2435);
PAINT MONO (-7735 2435);
FORCEPROP 0 LASTPIN (-7725 2475) $PN 150
J 2
(-7735 2485);
DISPLAY 0.680851 (-7735 2485);
PAINT MONO (-7735 2485);
FORCEPROP 0 LASTPIN (-7725 2525) $PN 220
J 2
(-7735 2535);
DISPLAY 0.680851 (-7735 2535);
PAINT MONO (-7735 2535);
FORCEPROP 0 LASTPIN (-7725 2575) $PN 231
J 2
(-7735 2585);
DISPLAY 0.680851 (-7735 2585);
PAINT MONO (-7735 2585);
FORCEPROP 0 LASTPIN (-7725 2625) $PN 232
J 2
(-7735 2635);
DISPLAY 0.680851 (-7735 2635);
PAINT MONO (-7735 2635);
FORCEPROP 0 LASTPIN (-7725 3125) $PN 3
J 2
(-7735 3135);
DISPLAY 0.680851 (-7735 3135);
PAINT MONO (-7735 3135);
FORCEPROP 2 LAST PART_TYPE SMLF
J 0
(-7575 6000);
DISPLAY 1.021277 (-7575 6000);
FORCEPROP 2 LAST VALUE SCONN288_DDR506112002KQ
J 0
(-7575 5950);
DISPLAY 0.489362 (-7575 5950);
PAINT SKYBLUE (-7575 5950);
FORCEPROP 1 LAST MATERIAL IO
J 0
(-7575 5750);
DISPLAY 0.468085 (-7575 5750);
PAINT SKYBLUE (-7575 5750);
FORCEPROP 1 LAST PART_NUMBER DFHST8FS479
J 0
(-7575 5825);
DISPLAY 0.468085 (-7575 5825);
PAINT SKYBLUE (-7575 5825);
FORCEPROP 1 LAST CDS_LMAN_SYM_OUTLINE -450,1900,450,-1850
J 0
(-7125 3825);
DISPLAY 0.468085 (-7125 3825);
PAINT GREEN (-7125 3825);
DISPLAY INVISIBLE (-7125 3825);
FORCEPROP 1 LAST PATH I348
J 0
(-7125 3825);
DISPLAY 0.723404 (-7125 3825);
PAINT GREEN (-7125 3825);
DISPLAY INVISIBLE (-7125 3825);
FORCEPROP 1 LAST NEEDS_NO_SIZE TRUE
J 0
(-7125 3825);
DISPLAY 0.723404 (-7125 3825);
PAINT GREEN (-7125 3825);
DISPLAY INVISIBLE (-7125 3825);
FORCEPROP 2 LAST CDS_LIB pure_quanta
J 0
(-7125 3825);
DISPLAY INVISIBLE (-7125 3825);
FORCEADD SCONN288_DDR506112002KQ..3
(-1400 3925);
FORCEPROP 1 LAST LOCATION J21
J 0
(-1850 5900);
DISPLAY 0.468085 (-1850 5900);
PAINT SKYBLUE (-1850 5900);
FORCEPROP 0 LAST $SEC 3
J 0
(-1850 6050);
DISPLAY 0.680851 (-1850 6050);
PAINT MONO (-1850 6050);
DISPLAY INVISIBLE (-1850 6050);
FORCEPROP 2 LAST CDS_SEC 3
J 0
(-1850 6050);
DISPLAY 1.021277 (-1850 6050);
DISPLAY INVISIBLE (-1850 6050);
FORCEPROP 0 LASTPIN (-800 2325) $PN G1
J 0
(-790 2335);
DISPLAY 0.680851 (-790 2335);
PAINT MONO (-790 2335);
FORCEPROP 0 LASTPIN (-800 2275) $PN G2
J 0
(-790 2285);
DISPLAY 0.680851 (-790 2285);
PAINT MONO (-790 2285);
FORCEPROP 0 LASTPIN (-800 2225) $PN G3
J 0
(-790 2235);
DISPLAY 0.680851 (-790 2235);
PAINT MONO (-790 2235);
FORCEPROP 0 LASTPIN (-2000 5475) $PN 1
J 2
(-2010 5485);
DISPLAY 0.680851 (-2010 5485);
PAINT MONO (-2010 5485);
FORCEPROP 0 LASTPIN (-2000 5525) $PN 145
J 2
(-2010 5535);
DISPLAY 0.680851 (-2010 5535);
PAINT MONO (-2010 5535);
FORCEPROP 0 LASTPIN (-2000 5575) $PN 146
J 2
(-2010 5585);
DISPLAY 0.680851 (-2010 5585);
PAINT MONO (-2010 5585);
FORCEPROP 0 LASTPIN (-800 2425) $PN 6
J 0
(-790 2435);
DISPLAY 0.680851 (-790 2435);
PAINT MONO (-790 2435);
FORCEPROP 0 LASTPIN (-800 2475) $PN 8
J 0
(-790 2485);
DISPLAY 0.680851 (-790 2485);
PAINT MONO (-790 2485);
FORCEPROP 0 LASTPIN (-800 2525) $PN 10
J 0
(-790 2535);
DISPLAY 0.680851 (-790 2535);
PAINT MONO (-790 2535);
FORCEPROP 0 LASTPIN (-800 2575) $PN 13
J 0
(-790 2585);
DISPLAY 0.680851 (-790 2585);
PAINT MONO (-790 2585);
FORCEPROP 0 LASTPIN (-800 2625) $PN 15
J 0
(-790 2635);
DISPLAY 0.680851 (-790 2635);
PAINT MONO (-790 2635);
FORCEPROP 0 LASTPIN (-800 2675) $PN 17
J 0
(-790 2685);
DISPLAY 0.680851 (-790 2685);
PAINT MONO (-790 2685);
FORCEPROP 0 LASTPIN (-800 2725) $PN 19
J 0
(-790 2735);
DISPLAY 0.680851 (-790 2735);
PAINT MONO (-790 2735);
FORCEPROP 0 LASTPIN (-800 2775) $PN 21
J 0
(-790 2785);
DISPLAY 0.680851 (-790 2785);
PAINT MONO (-790 2785);
FORCEPROP 0 LASTPIN (-800 2825) $PN 24
J 0
(-790 2835);
DISPLAY 0.680851 (-790 2835);
PAINT MONO (-790 2835);
FORCEPROP 0 LASTPIN (-800 2875) $PN 26
J 0
(-790 2885);
DISPLAY 0.680851 (-790 2885);
PAINT MONO (-790 2885);
FORCEPROP 0 LASTPIN (-800 2925) $PN 28
J 0
(-790 2935);
DISPLAY 0.680851 (-790 2935);
PAINT MONO (-790 2935);
FORCEPROP 0 LASTPIN (-800 2975) $PN 30
J 0
(-790 2985);
DISPLAY 0.680851 (-790 2985);
PAINT MONO (-790 2985);
FORCEPROP 0 LASTPIN (-800 3025) $PN 32
J 0
(-790 3035);
DISPLAY 0.680851 (-790 3035);
PAINT MONO (-790 3035);
FORCEPROP 0 LASTPIN (-800 3075) $PN 35
J 0
(-790 3085);
DISPLAY 0.680851 (-790 3085);
PAINT MONO (-790 3085);
FORCEPROP 0 LASTPIN (-800 3125) $PN 37
J 0
(-790 3135);
DISPLAY 0.680851 (-790 3135);
PAINT MONO (-790 3135);
FORCEPROP 0 LASTPIN (-800 3175) $PN 39
J 0
(-790 3185);
DISPLAY 0.680851 (-790 3185);
PAINT MONO (-790 3185);
FORCEPROP 0 LASTPIN (-800 3225) $PN 41
J 0
(-790 3235);
DISPLAY 0.680851 (-790 3235);
PAINT MONO (-790 3235);
FORCEPROP 0 LASTPIN (-800 3275) $PN 43
J 0
(-790 3285);
DISPLAY 0.680851 (-790 3285);
PAINT MONO (-790 3285);
FORCEPROP 0 LASTPIN (-800 3325) $PN 46
J 0
(-790 3335);
DISPLAY 0.680851 (-790 3335);
PAINT MONO (-790 3335);
FORCEPROP 0 LASTPIN (-800 3375) $PN 48
J 0
(-790 3385);
DISPLAY 0.680851 (-790 3385);
PAINT MONO (-790 3385);
FORCEPROP 0 LASTPIN (-800 3425) $PN 50
J 0
(-790 3435);
DISPLAY 0.680851 (-790 3435);
PAINT MONO (-790 3435);
FORCEPROP 0 LASTPIN (-800 3475) $PN 52
J 0
(-790 3485);
DISPLAY 0.680851 (-790 3485);
PAINT MONO (-790 3485);
FORCEPROP 0 LASTPIN (-800 3525) $PN 54
J 0
(-790 3535);
DISPLAY 0.680851 (-790 3535);
PAINT MONO (-790 3535);
FORCEPROP 0 LASTPIN (-800 3575) $PN 57
J 0
(-790 3585);
DISPLAY 0.680851 (-790 3585);
PAINT MONO (-790 3585);
FORCEPROP 0 LASTPIN (-800 3625) $PN 59
J 0
(-790 3635);
DISPLAY 0.680851 (-790 3635);
PAINT MONO (-790 3635);
FORCEPROP 0 LASTPIN (-800 3675) $PN 61
J 0
(-790 3685);
DISPLAY 0.680851 (-790 3685);
PAINT MONO (-790 3685);
FORCEPROP 0 LASTPIN (-800 3725) $PN 63
J 0
(-790 3735);
DISPLAY 0.680851 (-790 3735);
PAINT MONO (-790 3735);
FORCEPROP 0 LASTPIN (-800 3775) $PN 65
J 0
(-790 3785);
DISPLAY 0.680851 (-790 3785);
PAINT MONO (-790 3785);
FORCEPROP 0 LASTPIN (-800 3825) $PN 67
J 0
(-790 3835);
DISPLAY 0.680851 (-790 3835);
PAINT MONO (-790 3835);
FORCEPROP 0 LASTPIN (-800 3875) $PN 69
J 0
(-790 3885);
DISPLAY 0.680851 (-790 3885);
PAINT MONO (-790 3885);
FORCEPROP 0 LASTPIN (-800 3925) $PN 71
J 0
(-790 3935);
DISPLAY 0.680851 (-790 3935);
PAINT MONO (-790 3935);
FORCEPROP 0 LASTPIN (-800 3975) $PN 73
J 0
(-790 3985);
DISPLAY 0.680851 (-790 3985);
PAINT MONO (-790 3985);
FORCEPROP 0 LASTPIN (-800 4025) $PN 75
J 0
(-790 4035);
DISPLAY 0.680851 (-790 4035);
PAINT MONO (-790 4035);
FORCEPROP 0 LASTPIN (-800 4075) $PN 77
J 0
(-790 4085);
DISPLAY 0.680851 (-790 4085);
PAINT MONO (-790 4085);
FORCEPROP 0 LASTPIN (-800 4125) $PN 79
J 0
(-790 4135);
DISPLAY 0.680851 (-790 4135);
PAINT MONO (-790 4135);
FORCEPROP 0 LASTPIN (-800 4175) $PN 81
J 0
(-790 4185);
DISPLAY 0.680851 (-790 4185);
PAINT MONO (-790 4185);
FORCEPROP 0 LASTPIN (-800 4225) $PN 83
J 0
(-790 4235);
DISPLAY 0.680851 (-790 4235);
PAINT MONO (-790 4235);
FORCEPROP 0 LASTPIN (-800 4275) $PN 85
J 0
(-790 4285);
DISPLAY 0.680851 (-790 4285);
PAINT MONO (-790 4285);
FORCEPROP 0 LASTPIN (-800 4325) $PN 88
J 0
(-790 4335);
DISPLAY 0.680851 (-790 4335);
PAINT MONO (-790 4335);
FORCEPROP 0 LASTPIN (-800 4375) $PN 90
J 0
(-790 4385);
DISPLAY 0.680851 (-790 4385);
PAINT MONO (-790 4385);
FORCEPROP 0 LASTPIN (-800 4425) $PN 92
J 0
(-790 4435);
DISPLAY 0.680851 (-790 4435);
PAINT MONO (-790 4435);
FORCEPROP 0 LASTPIN (-800 4475) $PN 95
J 0
(-790 4485);
DISPLAY 0.680851 (-790 4485);
PAINT MONO (-790 4485);
FORCEPROP 0 LASTPIN (-800 4525) $PN 97
J 0
(-790 4535);
DISPLAY 0.680851 (-790 4535);
PAINT MONO (-790 4535);
FORCEPROP 0 LASTPIN (-800 4575) $PN 99
J 0
(-790 4585);
DISPLAY 0.680851 (-790 4585);
PAINT MONO (-790 4585);
FORCEPROP 0 LASTPIN (-800 4625) $PN 101
J 0
(-790 4635);
DISPLAY 0.680851 (-790 4635);
PAINT MONO (-790 4635);
FORCEPROP 0 LASTPIN (-800 4675) $PN 103
J 0
(-790 4685);
DISPLAY 0.680851 (-790 4685);
PAINT MONO (-790 4685);
FORCEPROP 0 LASTPIN (-800 4725) $PN 106
J 0
(-790 4735);
DISPLAY 0.680851 (-790 4735);
PAINT MONO (-790 4735);
FORCEPROP 0 LASTPIN (-800 4775) $PN 108
J 0
(-790 4785);
DISPLAY 0.680851 (-790 4785);
PAINT MONO (-790 4785);
FORCEPROP 0 LASTPIN (-800 4825) $PN 110
J 0
(-790 4835);
DISPLAY 0.680851 (-790 4835);
PAINT MONO (-790 4835);
FORCEPROP 0 LASTPIN (-800 4875) $PN 112
J 0
(-790 4885);
DISPLAY 0.680851 (-790 4885);
PAINT MONO (-790 4885);
FORCEPROP 0 LASTPIN (-800 4925) $PN 114
J 0
(-790 4935);
DISPLAY 0.680851 (-790 4935);
PAINT MONO (-790 4935);
FORCEPROP 0 LASTPIN (-800 4975) $PN 117
J 0
(-790 4985);
DISPLAY 0.680851 (-790 4985);
PAINT MONO (-790 4985);
FORCEPROP 0 LASTPIN (-800 5025) $PN 119
J 0
(-790 5035);
DISPLAY 0.680851 (-790 5035);
PAINT MONO (-790 5035);
FORCEPROP 0 LASTPIN (-800 5075) $PN 121
J 0
(-790 5085);
DISPLAY 0.680851 (-790 5085);
PAINT MONO (-790 5085);
FORCEPROP 0 LASTPIN (-800 5125) $PN 123
J 0
(-790 5135);
DISPLAY 0.680851 (-790 5135);
PAINT MONO (-790 5135);
FORCEPROP 0 LASTPIN (-800 5175) $PN 125
J 0
(-790 5185);
DISPLAY 0.680851 (-790 5185);
PAINT MONO (-790 5185);
FORCEPROP 0 LASTPIN (-800 5225) $PN 128
J 0
(-790 5235);
DISPLAY 0.680851 (-790 5235);
PAINT MONO (-790 5235);
FORCEPROP 0 LASTPIN (-800 5275) $PN 130
J 0
(-790 5285);
DISPLAY 0.680851 (-790 5285);
PAINT MONO (-790 5285);
FORCEPROP 0 LASTPIN (-800 5325) $PN 132
J 0
(-790 5335);
DISPLAY 0.680851 (-790 5335);
PAINT MONO (-790 5335);
FORCEPROP 0 LASTPIN (-800 5375) $PN 134
J 0
(-790 5385);
DISPLAY 0.680851 (-790 5385);
PAINT MONO (-790 5385);
FORCEPROP 0 LASTPIN (-800 5425) $PN 136
J 0
(-790 5435);
DISPLAY 0.680851 (-790 5435);
PAINT MONO (-790 5435);
FORCEPROP 0 LASTPIN (-800 5475) $PN 139
J 0
(-790 5485);
DISPLAY 0.680851 (-790 5485);
PAINT MONO (-790 5485);
FORCEPROP 0 LASTPIN (-800 5525) $PN 141
J 0
(-790 5535);
DISPLAY 0.680851 (-790 5535);
PAINT MONO (-790 5535);
FORCEPROP 0 LASTPIN (-800 5575) $PN 143
J 0
(-790 5585);
DISPLAY 0.680851 (-790 5585);
PAINT MONO (-790 5585);
FORCEPROP 0 LASTPIN (-2000 2325) $PN 151
J 2
(-2010 2335);
DISPLAY 0.680851 (-2010 2335);
PAINT MONO (-2010 2335);
FORCEPROP 0 LASTPIN (-2000 2375) $PN 153
J 2
(-2010 2385);
DISPLAY 0.680851 (-2010 2385);
PAINT MONO (-2010 2385);
FORCEPROP 0 LASTPIN (-2000 2425) $PN 155
J 2
(-2010 2435);
DISPLAY 0.680851 (-2010 2435);
PAINT MONO (-2010 2435);
FORCEPROP 0 LASTPIN (-2000 2475) $PN 158
J 2
(-2010 2485);
DISPLAY 0.680851 (-2010 2485);
PAINT MONO (-2010 2485);
FORCEPROP 0 LASTPIN (-2000 2525) $PN 160
J 2
(-2010 2535);
DISPLAY 0.680851 (-2010 2535);
PAINT MONO (-2010 2535);
FORCEPROP 0 LASTPIN (-2000 2575) $PN 162
J 2
(-2010 2585);
DISPLAY 0.680851 (-2010 2585);
PAINT MONO (-2010 2585);
FORCEPROP 0 LASTPIN (-2000 2625) $PN 164
J 2
(-2010 2635);
DISPLAY 0.680851 (-2010 2635);
PAINT MONO (-2010 2635);
FORCEPROP 0 LASTPIN (-2000 2675) $PN 166
J 2
(-2010 2685);
DISPLAY 0.680851 (-2010 2685);
PAINT MONO (-2010 2685);
FORCEPROP 0 LASTPIN (-2000 2725) $PN 169
J 2
(-2010 2735);
DISPLAY 0.680851 (-2010 2735);
PAINT MONO (-2010 2735);
FORCEPROP 0 LASTPIN (-2000 2775) $PN 171
J 2
(-2010 2785);
DISPLAY 0.680851 (-2010 2785);
PAINT MONO (-2010 2785);
FORCEPROP 0 LASTPIN (-2000 2825) $PN 173
J 2
(-2010 2835);
DISPLAY 0.680851 (-2010 2835);
PAINT MONO (-2010 2835);
FORCEPROP 0 LASTPIN (-2000 2875) $PN 175
J 2
(-2010 2885);
DISPLAY 0.680851 (-2010 2885);
PAINT MONO (-2010 2885);
FORCEPROP 0 LASTPIN (-2000 2925) $PN 177
J 2
(-2010 2935);
DISPLAY 0.680851 (-2010 2935);
PAINT MONO (-2010 2935);
FORCEPROP 0 LASTPIN (-2000 2975) $PN 180
J 2
(-2010 2985);
DISPLAY 0.680851 (-2010 2985);
PAINT MONO (-2010 2985);
FORCEPROP 0 LASTPIN (-2000 3025) $PN 182
J 2
(-2010 3035);
DISPLAY 0.680851 (-2010 3035);
PAINT MONO (-2010 3035);
FORCEPROP 0 LASTPIN (-2000 3075) $PN 184
J 2
(-2010 3085);
DISPLAY 0.680851 (-2010 3085);
PAINT MONO (-2010 3085);
FORCEPROP 0 LASTPIN (-2000 3125) $PN 186
J 2
(-2010 3135);
DISPLAY 0.680851 (-2010 3135);
PAINT MONO (-2010 3135);
FORCEPROP 0 LASTPIN (-2000 3175) $PN 188
J 2
(-2010 3185);
DISPLAY 0.680851 (-2010 3185);
PAINT MONO (-2010 3185);
FORCEPROP 0 LASTPIN (-2000 3225) $PN 191
J 2
(-2010 3235);
DISPLAY 0.680851 (-2010 3235);
PAINT MONO (-2010 3235);
FORCEPROP 0 LASTPIN (-2000 3275) $PN 193
J 2
(-2010 3285);
DISPLAY 0.680851 (-2010 3285);
PAINT MONO (-2010 3285);
FORCEPROP 0 LASTPIN (-2000 3325) $PN 195
J 2
(-2010 3335);
DISPLAY 0.680851 (-2010 3335);
PAINT MONO (-2010 3335);
FORCEPROP 0 LASTPIN (-2000 3375) $PN 197
J 2
(-2010 3385);
DISPLAY 0.680851 (-2010 3385);
PAINT MONO (-2010 3385);
FORCEPROP 0 LASTPIN (-2000 3425) $PN 199
J 2
(-2010 3435);
DISPLAY 0.680851 (-2010 3435);
PAINT MONO (-2010 3435);
FORCEPROP 0 LASTPIN (-2000 3475) $PN 202
J 2
(-2010 3485);
DISPLAY 0.680851 (-2010 3485);
PAINT MONO (-2010 3485);
FORCEPROP 0 LASTPIN (-2000 3525) $PN 204
J 2
(-2010 3535);
DISPLAY 0.680851 (-2010 3535);
PAINT MONO (-2010 3535);
FORCEPROP 0 LASTPIN (-2000 3575) $PN 206
J 2
(-2010 3585);
DISPLAY 0.680851 (-2010 3585);
PAINT MONO (-2010 3585);
FORCEPROP 0 LASTPIN (-2000 3625) $PN 208
J 2
(-2010 3635);
DISPLAY 0.680851 (-2010 3635);
PAINT MONO (-2010 3635);
FORCEPROP 0 LASTPIN (-2000 3675) $PN 210
J 2
(-2010 3685);
DISPLAY 0.680851 (-2010 3685);
PAINT MONO (-2010 3685);
FORCEPROP 0 LASTPIN (-2000 3725) $PN 212
J 2
(-2010 3735);
DISPLAY 0.680851 (-2010 3735);
PAINT MONO (-2010 3735);
FORCEPROP 0 LASTPIN (-2000 3775) $PN 214
J 2
(-2010 3785);
DISPLAY 0.680851 (-2010 3785);
PAINT MONO (-2010 3785);
FORCEPROP 0 LASTPIN (-2000 3825) $PN 216
J 2
(-2010 3835);
DISPLAY 0.680851 (-2010 3835);
PAINT MONO (-2010 3835);
FORCEPROP 0 LASTPIN (-2000 3875) $PN 219
J 2
(-2010 3885);
DISPLAY 0.680851 (-2010 3885);
PAINT MONO (-2010 3885);
FORCEPROP 0 LASTPIN (-2000 3925) $PN 222
J 2
(-2010 3935);
DISPLAY 0.680851 (-2010 3935);
PAINT MONO (-2010 3935);
FORCEPROP 0 LASTPIN (-2000 3975) $PN 224
J 2
(-2010 3985);
DISPLAY 0.680851 (-2010 3985);
PAINT MONO (-2010 3985);
FORCEPROP 0 LASTPIN (-2000 4025) $PN 226
J 2
(-2010 4035);
DISPLAY 0.680851 (-2010 4035);
PAINT MONO (-2010 4035);
FORCEPROP 0 LASTPIN (-2000 4075) $PN 228
J 2
(-2010 4085);
DISPLAY 0.680851 (-2010 4085);
PAINT MONO (-2010 4085);
FORCEPROP 0 LASTPIN (-2000 4125) $PN 230
J 2
(-2010 4135);
DISPLAY 0.680851 (-2010 4135);
PAINT MONO (-2010 4135);
FORCEPROP 0 LASTPIN (-2000 4175) $PN 233
J 2
(-2010 4185);
DISPLAY 0.680851 (-2010 4185);
PAINT MONO (-2010 4185);
FORCEPROP 0 LASTPIN (-2000 4225) $PN 235
J 2
(-2010 4235);
DISPLAY 0.680851 (-2010 4235);
PAINT MONO (-2010 4235);
FORCEPROP 0 LASTPIN (-2000 4275) $PN 237
J 2
(-2010 4285);
DISPLAY 0.680851 (-2010 4285);
PAINT MONO (-2010 4285);
FORCEPROP 0 LASTPIN (-2000 4325) $PN 240
J 2
(-2010 4335);
DISPLAY 0.680851 (-2010 4335);
PAINT MONO (-2010 4335);
FORCEPROP 0 LASTPIN (-2000 4375) $PN 242
J 2
(-2010 4385);
DISPLAY 0.680851 (-2010 4385);
PAINT MONO (-2010 4385);
FORCEPROP 0 LASTPIN (-2000 4425) $PN 244
J 2
(-2010 4435);
DISPLAY 0.680851 (-2010 4435);
PAINT MONO (-2010 4435);
FORCEPROP 0 LASTPIN (-2000 4475) $PN 246
J 2
(-2010 4485);
DISPLAY 0.680851 (-2010 4485);
PAINT MONO (-2010 4485);
FORCEPROP 0 LASTPIN (-2000 4525) $PN 248
J 2
(-2010 4535);
DISPLAY 0.680851 (-2010 4535);
PAINT MONO (-2010 4535);
FORCEPROP 0 LASTPIN (-2000 4575) $PN 251
J 2
(-2010 4585);
DISPLAY 0.680851 (-2010 4585);
PAINT MONO (-2010 4585);
FORCEPROP 0 LASTPIN (-2000 4625) $PN 253
J 2
(-2010 4635);
DISPLAY 0.680851 (-2010 4635);
PAINT MONO (-2010 4635);
FORCEPROP 0 LASTPIN (-2000 4675) $PN 255
J 2
(-2010 4685);
DISPLAY 0.680851 (-2010 4685);
PAINT MONO (-2010 4685);
FORCEPROP 0 LASTPIN (-2000 4725) $PN 257
J 2
(-2010 4735);
DISPLAY 0.680851 (-2010 4735);
PAINT MONO (-2010 4735);
FORCEPROP 0 LASTPIN (-2000 4775) $PN 259
J 2
(-2010 4785);
DISPLAY 0.680851 (-2010 4785);
PAINT MONO (-2010 4785);
FORCEPROP 0 LASTPIN (-2000 4825) $PN 262
J 2
(-2010 4835);
DISPLAY 0.680851 (-2010 4835);
PAINT MONO (-2010 4835);
FORCEPROP 0 LASTPIN (-2000 4875) $PN 264
J 2
(-2010 4885);
DISPLAY 0.680851 (-2010 4885);
PAINT MONO (-2010 4885);
FORCEPROP 0 LASTPIN (-2000 4925) $PN 266
J 2
(-2010 4935);
DISPLAY 0.680851 (-2010 4935);
PAINT MONO (-2010 4935);
FORCEPROP 0 LASTPIN (-2000 4975) $PN 268
J 2
(-2010 4985);
DISPLAY 0.680851 (-2010 4985);
PAINT MONO (-2010 4985);
FORCEPROP 0 LASTPIN (-2000 5025) $PN 270
J 2
(-2010 5035);
DISPLAY 0.680851 (-2010 5035);
PAINT MONO (-2010 5035);
FORCEPROP 0 LASTPIN (-2000 5075) $PN 273
J 2
(-2010 5085);
DISPLAY 0.680851 (-2010 5085);
PAINT MONO (-2010 5085);
FORCEPROP 0 LASTPIN (-2000 5125) $PN 275
J 2
(-2010 5135);
DISPLAY 0.680851 (-2010 5135);
PAINT MONO (-2010 5135);
FORCEPROP 0 LASTPIN (-2000 5175) $PN 277
J 2
(-2010 5185);
DISPLAY 0.680851 (-2010 5185);
PAINT MONO (-2010 5185);
FORCEPROP 0 LASTPIN (-2000 5225) $PN 279
J 2
(-2010 5235);
DISPLAY 0.680851 (-2010 5235);
PAINT MONO (-2010 5235);
FORCEPROP 0 LASTPIN (-2000 5275) $PN 281
J 2
(-2010 5285);
DISPLAY 0.680851 (-2010 5285);
PAINT MONO (-2010 5285);
FORCEPROP 0 LASTPIN (-2000 5325) $PN 284
J 2
(-2010 5335);
DISPLAY 0.680851 (-2010 5335);
PAINT MONO (-2010 5335);
FORCEPROP 0 LASTPIN (-2000 5375) $PN 286
J 2
(-2010 5385);
DISPLAY 0.680851 (-2010 5385);
PAINT MONO (-2010 5385);
FORCEPROP 0 LASTPIN (-2000 5425) $PN 288
J 2
(-2010 5435);
DISPLAY 0.680851 (-2010 5435);
PAINT MONO (-2010 5435);
FORCEPROP 2 LAST PART_TYPE SMLF
J 0
(-1850 6000);
DISPLAY 1.021277 (-1850 6000);
FORCEPROP 2 LAST VALUE SCONN288_DDR506112002KQ
J 0
(-1850 5950);
DISPLAY 0.489362 (-1850 5950);
PAINT SKYBLUE (-1850 5950);
FORCEPROP 1 LAST MATERIAL IO
J 0
(-1850 5750);
DISPLAY 0.468085 (-1850 5750);
PAINT SKYBLUE (-1850 5750);
FORCEPROP 1 LAST PART_NUMBER DFHST8FS479
J 0
(-1850 5825);
DISPLAY 0.468085 (-1850 5825);
PAINT SKYBLUE (-1850 5825);
FORCEPROP 1 LAST CDS_LMAN_SYM_OUTLINE -450,1800,450,-1750
J 0
(-1400 3925);
DISPLAY 0.468085 (-1400 3925);
PAINT GREEN (-1400 3925);
DISPLAY INVISIBLE (-1400 3925);
FORCEPROP 1 LAST PATH I350
J 0
(-1400 3925);
DISPLAY 0.723404 (-1400 3925);
PAINT GREEN (-1400 3925);
DISPLAY INVISIBLE (-1400 3925);
FORCEPROP 1 LAST NEEDS_NO_SIZE TRUE
J 0
(-1400 3925);
DISPLAY 0.723404 (-1400 3925);
PAINT GREEN (-1400 3925);
DISPLAY INVISIBLE (-1400 3925);
FORCEPROP 2 LAST CDS_LIB pure_quanta
J 0
(-1400 3925);
DISPLAY INVISIBLE (-1400 3925);
FORCEADD OFFPAGE..5
(-8425 3225);
FORCEPROP 2 LAST $XR0 14 
J 0
(-8649 3225);
DISPLAY 0.638298 (-8649 3225);
PAINT MONO (-8649 3225);
FORCEPROP 2 LAST PATH I351
J 0
(-8375 3300);
DISPLAY 1.021277 (-8375 3300);
DISPLAY INVISIBLE (-8375 3300);
FORCEPROP 1 LAST COMMENT_BODY TRUE
J 0
(-8325 3150);
DISPLAY 0.872340 (-8325 3150);
PAINT GREEN (-8325 3150);
DISPLAY INVISIBLE (-8325 3150);
FORCEPROP 1 LAST OFFPAGE TRUE
J 0
(-8100 3100);
DISPLAY 0.872340 (-8100 3100);
PAINT GREEN (-8100 3100);
DISPLAY INVISIBLE (-8100 3100);
FORCEPROP 2 LAST CDS_LIB mstr_standard
J 0
(-8425 3225);
DISPLAY INVISIBLE (-8425 3225);
FORCEADD OFFPAGE..6
(-8575 3025);
FORCEPROP 2 LAST $XR5 136 
J 0
(-9334 3025);
DISPLAY 0.638298 (-9334 3025);
PAINT MONO (-9334 3025);
FORCEPROP 2 LAST $XR4 90 
J 0
(-9214 3025);
DISPLAY 0.638298 (-9214 3025);
PAINT MONO (-9214 3025);
FORCEPROP 2 LAST $XR3 88 
J 0
(-9124 3025);
DISPLAY 0.638298 (-9124 3025);
PAINT MONO (-9124 3025);
FORCEPROP 2 LAST $XR2 87 
J 0
(-9034 3025);
DISPLAY 0.638298 (-9034 3025);
PAINT MONO (-9034 3025);
FORCEPROP 2 LAST $XR1 86 
J 0
(-8944 3025);
DISPLAY 0.638298 (-8944 3025);
PAINT MONO (-8944 3025);
FORCEPROP 2 LAST $XR0 85 
J 0
(-8854 3025);
DISPLAY 0.638298 (-8854 3025);
PAINT MONO (-8854 3025);
FORCEPROP 2 LAST PATH I353
J 0
(-8850 3075);
DISPLAY 1.021277 (-8850 3075);
DISPLAY INVISIBLE (-8850 3075);
FORCEPROP 1 LAST COMMENT_BODY TRUE
J 0
(-8475 2950);
DISPLAY 0.872340 (-8475 2950);
PAINT GREEN (-8475 2950);
DISPLAY INVISIBLE (-8475 2950);
FORCEPROP 1 LAST OFFPAGE TRUE
J 0
(-8250 2900);
DISPLAY 0.872340 (-8250 2900);
PAINT GREEN (-8250 2900);
DISPLAY INVISIBLE (-8250 2900);
FORCEPROP 2 LAST CDS_LIB mstr_standard
J 0
(-8575 3025);
DISPLAY 0.808511 (-8575 3025);
DISPLAY INVISIBLE (-8575 3025);
FORCEADD GND..1
(-8875 3175);
FORCEPROP 3 LASTPIN (-8875 3225) SIG_NAME GND\g
J 0
(-8865 3235);
DISPLAY 0.659574 (-8865 3235);
PAINT MONO (-8865 3235);
DISPLAY INVISIBLE (-8865 3235);
FORCEPROP 2 LAST BOM_COST MEM
J 0
(-8850 3300);
DISPLAY 0.659574 (-8850 3300);
DISPLAY INVISIBLE (-8850 3300);
FORCEPROP 1 LAST SIZE 1B
J 0
(-8800 3125);
DISPLAY 0.723404 (-8800 3125);
PAINT GREEN (-8800 3125);
DISPLAY INVISIBLE (-8800 3125);
FORCEPROP 2 LAST CDS_LIB mstr_symbols
J 0
(-8875 3175);
DISPLAY 0.808511 (-8875 3175);
DISPLAY INVISIBLE (-8875 3175);
FORCEPROP 1 LAST BODY_TYPE PLUMBING
J 0
(-8920 3132);
DISPLAY 0.276596 (-8920 3132);
PAINT GREEN (-8920 3132);
DISPLAY INVISIBLE (-8920 3132);
FORCEPROP 1 LAST PATH I359
J 0
(-8800 3175);
DISPLAY 0.872340 (-8800 3175);
PAINT AQUA (-8800 3175);
DISPLAY INVISIBLE (-8800 3175);
FORCEPROP 1 LAST VOLTAGE 0
J 0
(-8895 3270);
DISPLAY 0.829787 (-8895 3270);
PAINT SKYBLUE (-8895 3270);
DISPLAY INVISIBLE (-8895 3270);
FORCEPROP 2 LAST ROOM MEM_EFGH_DECOUPLING_CAPS
J 0
(-8850 3250);
DISPLAY 0.659574 (-8850 3250);
PAINT RED (-8850 3250);
DISPLAY INVISIBLE (-8850 3250);
FORCEPROP 1 LAST HDL_POWER GND
J 0
(-8875 3325);
DISPLAY 0.723404 (-8875 3325);
PAINT GREEN (-8875 3325);
DISPLAY INVISIBLE (-8875 3325);
FORCEADD Q_CAP..1
R 2
(-8875 3400);
FORCEPROP 1 LAST LOCATION C104
J 2
(-8925 3500);
DISPLAY 0.489362 (-8925 3500);
PAINT SKYBLUE (-8925 3500);
FORCEPROP 0 LAST $SEC 1
J 0
(-8925 3550);
DISPLAY 0.680851 (-8925 3550);
PAINT MONO (-8925 3550);
DISPLAY INVISIBLE (-8925 3550);
FORCEPROP 0 LAST CDS_SEC 1
J 0
(-8925 3550);
DISPLAY 1.021277 (-8925 3550);
DISPLAY INVISIBLE (-8925 3550);
FORCEPROP 1 LASTPIN (-8875 3500) $PN 1
J 2
(-8885 3480);
DISPLAY 0.489362 (-8885 3480);
PAINT MONO (-8885 3480);
FORCEPROP 1 LASTPIN (-8875 3300) $PN 2
J 2
(-8885 3280);
DISPLAY 0.489362 (-8885 3280);
PAINT MONO (-8885 3280);
FORCEPROP 1 LAST VALUE 0.1UF
J 2
(-8925 3450);
DISPLAY 0.489362 (-8925 3450);
PAINT SKYBLUE (-8925 3450);
FORCEPROP 1 LAST VOLTAGE 25V
J 2
(-8925 3400);
DISPLAY 0.489362 (-8925 3400);
PAINT SKYBLUE (-8925 3400);
FORCEPROP 1 LAST MATERIAL X7R
J 2
(-8925 3300);
DISPLAY 0.489362 (-8925 3300);
PAINT SKYBLUE (-8925 3300);
FORCEPROP 1 LAST TOLERANCE 10%
J 2
(-8925 3350);
DISPLAY 0.489362 (-8925 3350);
PAINT SKYBLUE (-8925 3350);
FORCEPROP 1 LAST PACK_TYPE 0402
J 2
(-8925 3200);
DISPLAY 0.489362 (-8925 3200);
PAINT SKYBLUE (-8925 3200);
FORCEPROP 1 LAST PART_NUMBER CH4104K1B00
J 2
(-8925 3250);
DISPLAY 0.489362 (-8925 3250);
PAINT SKYBLUE (-8925 3250);
FORCEPROP 0 LAST BOM_COST MEM
J 2
(-8930 3545);
DISPLAY 0.595745 (-8930 3545);
PAINT MONO (-8930 3545);
DISPLAY INVISIBLE (-8930 3545);
FORCEPROP 2 LAST CDS_LIB pure_quanta
J 0
(-8875 3400);
DISPLAY INVISIBLE (-8875 3400);
FORCEPROP 1 LAST PATH I360
J 2
(-8925 3550);
DISPLAY 0.978723 (-8925 3550);
PAINT WHITE (-8925 3550);
DISPLAY INVISIBLE (-8925 3550);
FORCEPROP 0 LAST ROOM MEM_CH_A_CPU0_DIMM1
J 2
(-8930 3545);
DISPLAY 0.595745 (-8930 3545);
PAINT RED (-8930 3545);
DISPLAY INVISIBLE (-8930 3545);
FORCEADD OFFPAGE..6
(-9225 2325);
FORCEPROP 2 LAST $XR5 81 
J 0
(-9534 2217);
DISPLAY 0.638298 (-9534 2217);
PAINT MONO (-9534 2217);
FORCEPROP 2 LAST $XR4 90 
J 0
(-9534 2397);
DISPLAY 0.638298 (-9534 2397);
PAINT MONO (-9534 2397);
FORCEPROP 2 LAST $XR3 88 
J 0
(-9534 2253);
DISPLAY 0.638298 (-9534 2253);
PAINT MONO (-9534 2253);
FORCEPROP 2 LAST $XR2 87 
J 0
(-9534 2361);
DISPLAY 0.638298 (-9534 2361);
PAINT MONO (-9534 2361);
FORCEPROP 2 LAST $XR1 86 
J 0
(-9534 2289);
DISPLAY 0.638298 (-9534 2289);
PAINT MONO (-9534 2289);
FORCEPROP 2 LAST $XR0 85 
J 0
(-9534 2325);
DISPLAY 0.638298 (-9534 2325);
PAINT MONO (-9534 2325);
FORCEPROP 2 LAST PATH I361
J 0
(-9175 2400);
DISPLAY 1.021277 (-9175 2400);
DISPLAY INVISIBLE (-9175 2400);
FORCEPROP 1 LAST COMMENT_BODY TRUE
J 0
(-9125 2250);
DISPLAY 0.872340 (-9125 2250);
PAINT GREEN (-9125 2250);
DISPLAY INVISIBLE (-9125 2250);
FORCEPROP 1 LAST OFFPAGE TRUE
J 0
(-8900 2200);
DISPLAY 0.872340 (-8900 2200);
PAINT GREEN (-8900 2200);
DISPLAY INVISIBLE (-8900 2200);
FORCEPROP 2 LAST CDS_LIB mstr_standard
J 0
(-9225 2325);
DISPLAY INVISIBLE (-9225 2325);
FORCEADD Q_RES..1
R 2
(-8725 2325);
FORCEPROP 1 LAST LOCATION R295
J 2
(-8675 2375);
DISPLAY 0.489362 (-8675 2375);
PAINT SKYBLUE (-8675 2375);
FORCEPROP 0 LAST $SEC 1
J 0
(-8675 2425);
DISPLAY 0.680851 (-8675 2425);
PAINT MONO (-8675 2425);
DISPLAY INVISIBLE (-8675 2425);
FORCEPROP 0 LAST CDS_SEC 1
J 0
(-8675 2425);
DISPLAY 1.021277 (-8675 2425);
DISPLAY INVISIBLE (-8675 2425);
FORCEPROP 1 LASTPIN (-8625 2325) $PN 1
J 2
(-8637 2337);
DISPLAY 0.489362 (-8637 2337);
PAINT MONO (-8637 2337);
FORCEPROP 1 LASTPIN (-8825 2325) $PN 2
J 2
(-8787 2337);
DISPLAY 0.489362 (-8787 2337);
PAINT MONO (-8787 2337);
FORCEPROP 1 LAST VALUE 0
J 0
(-8725 2275);
DISPLAY 0.489362 (-8725 2275);
PAINT SKYBLUE (-8725 2275);
FORCEPROP 2 LAST CDS_LIB pure_quanta
J 0
(-8725 2325);
DISPLAY INVISIBLE (-8725 2325);
FORCEPROP 2 LAST BOM_COST MEM
J 0
(-8750 2475);
DISPLAY 0.744681 (-8750 2475);
PAINT WHITE (-8750 2475);
DISPLAY INVISIBLE (-8750 2475);
FORCEPROP 1 LAST PATH I362
J 2
(-8675 2475);
DISPLAY 0.978723 (-8675 2475);
PAINT WHITE (-8675 2475);
DISPLAY INVISIBLE (-8675 2475);
FORCEPROP 1 LAST WATTAGE 1/16W
J 0
(-8650 2250);
DISPLAY 0.489362 (-8650 2250);
PAINT SKYBLUE (-8650 2250);
DISPLAY INVISIBLE (-8650 2250);
FORCEPROP 1 LAST MATERIAL CHIP
J 0
(-8900 2300);
DISPLAY 0.489362 (-8900 2300);
PAINT SKYBLUE (-8900 2300);
DISPLAY INVISIBLE (-8900 2300);
FORCEPROP 1 LAST TOLERANCE 5%
J 2
(-8600 2300);
DISPLAY 0.489362 (-8600 2300);
PAINT SKYBLUE (-8600 2300);
DISPLAY INVISIBLE (-8600 2300);
FORCEPROP 1 LAST PART_NUMBER CS00002JB38
J 0
(-8825 2375);
DISPLAY 0.489362 (-8825 2375);
PAINT SKYBLUE (-8825 2375);
DISPLAY INVISIBLE (-8825 2375);
FORCEPROP 1 LAST PACK_TYPE 0402LF
J 0
(-8900 2250);
DISPLAY 0.489362 (-8900 2250);
PAINT SKYBLUE (-8900 2250);
DISPLAY INVISIBLE (-8900 2250);
FORCEPROP 2 LAST ROOM RST_CPU0_PLD_TO_DIMM
J 0
(-8750 2425);
DISPLAY 0.744681 (-8750 2425);
PAINT RED (-8750 2425);
DISPLAY INVISIBLE (-8750 2425);
FORCEADD VCC_CORE..1
(-8600 2650);
FORCEPROP 3 LASTPIN (-8600 2600) SIG_NAME P3V3_STBY\g
J 0
(-8590 2610);
DISPLAY 0.659574 (-8590 2610);
PAINT MONO (-8590 2610);
DISPLAY INVISIBLE (-8590 2610);
FORCEPROP 1 LAST HDL_POWER P3V3_STBY
J 1
(-8600 2700);
DISPLAY 0.489362 (-8600 2700);
PAINT GREEN (-8600 2700);
FORCEPROP 2 LAST CDS_LIB mstr_symbols
J 0
(-8600 2650);
DISPLAY INVISIBLE (-8600 2650);
FORCEPROP 1 LAST PATH I363
J 0
(-8550 2675);
DISPLAY 0.872340 (-8550 2675);
PAINT AQUA (-8550 2675);
DISPLAY INVISIBLE (-8550 2675);
FORCEPROP 0 LAST VOLTAGE 3.3
J 0
(-8875 2800);
DISPLAY 1.021277 (-8875 2800);
PAINT SKYBLUE (-8875 2800);
DISPLAY INVISIBLE (-8875 2800);
FORCEPROP 2 LAST ROOM PVCCINFAON_CPU0_CTRL
J 0
(-8600 2750);
DISPLAY 0.808511 (-8600 2750);
PAINT RED (-8600 2750);
DISPLAY INVISIBLE (-8600 2750);
FORCEADD Q_RES..2
(-8600 2475);
FORCEPROP 1 LAST LOCATION R93
J 0
(-8555 2600);
DISPLAY 0.489362 (-8555 2600);
PAINT SKYBLUE (-8555 2600);
FORCEPROP 0 LAST $SEC 1
J 0
(-8550 2650);
DISPLAY 0.680851 (-8550 2650);
PAINT MONO (-8550 2650);
DISPLAY INVISIBLE (-8550 2650);
FORCEPROP 0 LAST CDS_SEC 1
J 0
(-8550 2650);
DISPLAY 1.021277 (-8550 2650);
DISPLAY INVISIBLE (-8550 2650);
FORCEPROP 1 LASTPIN (-8600 2575) $PN 1
J 0
(-8595 2537);
DISPLAY 0.489362 (-8595 2537);
PAINT MONO (-8595 2537);
FORCEPROP 1 LASTPIN (-8600 2375) $PN 2
J 0
(-8595 2385);
DISPLAY 0.489362 (-8595 2385);
PAINT MONO (-8595 2385);
FORCEPROP 1 LAST WATTAGE 1/16W
J 0
(-8550 2500);
DISPLAY 0.489362 (-8550 2500);
PAINT SKYBLUE (-8550 2500);
FORCEPROP 1 LAST MATERIAL EMPTY
J 0
(-8550 2475);
DISPLAY 0.489362 (-8550 2475);
PAINT RED (-8550 2475);
FORCEPROP 1 LAST TOLERANCE 5%
J 0
(-8550 2525);
DISPLAY 0.489362 (-8550 2525);
PAINT SKYBLUE (-8550 2525);
FORCEPROP 1 LAST VALUE 1K
J 0
(-8555 2550);
DISPLAY 0.489362 (-8555 2550);
PAINT SKYBLUE (-8555 2550);
FORCEPROP 1 LAST PACK_TYPE 0402LF
J 0
(-8550 2425);
DISPLAY 0.489362 (-8550 2425);
PAINT SKYBLUE (-8550 2425);
FORCEPROP 2 LAST CDS_LIB pure_quanta
J 0
(-8600 2475);
DISPLAY INVISIBLE (-8600 2475);
FORCEPROP 2 LAST BOM_COST MEM
J 0
(-8550 2650);
DISPLAY 0.808511 (-8550 2650);
DISPLAY INVISIBLE (-8550 2650);
FORCEPROP 1 LAST PATH I364
J 0
(-8550 2650);
DISPLAY 0.978723 (-8550 2650);
PAINT WHITE (-8550 2650);
DISPLAY INVISIBLE (-8550 2650);
FORCEPROP 1 LAST PART_NUMBER TMP_QCS21002JB34
J 0
(-8550 2450);
DISPLAY 0.489362 (-8550 2450);
PAINT SKYBLUE (-8550 2450);
DISPLAY INVISIBLE (-8550 2450);
FORCEPROP 2 LAST ROOM MEM_CH_A_CPU0_DIMM1
J 0
(-8550 2700);
DISPLAY 0.808511 (-8550 2700);
PAINT RED (-8550 2700);
DISPLAY INVISIBLE (-8550 2700);
FORCEADD OFFPAGE..2
(-2675 4725);
FORCEPROP 2 LAST $XR0 14 
J 0
(-2486 4725);
DISPLAY 0.638298 (-2486 4725);
PAINT MONO (-2486 4725);
FORCEPROP 2 LAST PATH I366
J 0
(-2475 4775);
DISPLAY 0.680851 (-2475 4775);
DISPLAY INVISIBLE (-2475 4775);
FORCEPROP 1 LAST COMMENT_BODY TRUE
J 0
(-2720 4630);
DISPLAY 0.872340 (-2720 4630);
PAINT GREEN (-2720 4630);
DISPLAY INVISIBLE (-2720 4630);
FORCEPROP 1 LAST OFFPAGE TRUE
J 0
(-2350 4600);
DISPLAY 0.723404 (-2350 4600);
PAINT GREEN (-2350 4600);
DISPLAY INVISIBLE (-2350 4600);
FORCEPROP 2 LAST CDS_LIB mstr_standard
J 0
(-2675 4725);
DISPLAY 0.723404 (-2675 4725);
PAINT MONO (-2675 4725);
DISPLAY INVISIBLE (-2675 4725);
FORCEADD OFFPAGE..2
(-2675 4675);
FORCEPROP 2 LAST $XR0 14 
J 0
(-2486 4675);
DISPLAY 0.638298 (-2486 4675);
PAINT MONO (-2486 4675);
FORCEPROP 2 LAST PATH I367
J 0
(-2475 4725);
DISPLAY 0.680851 (-2475 4725);
DISPLAY INVISIBLE (-2475 4725);
FORCEPROP 1 LAST COMMENT_BODY TRUE
J 0
(-2720 4580);
DISPLAY 0.872340 (-2720 4580);
PAINT GREEN (-2720 4580);
DISPLAY INVISIBLE (-2720 4580);
FORCEPROP 1 LAST OFFPAGE TRUE
J 0
(-2350 4550);
DISPLAY 0.723404 (-2350 4550);
PAINT GREEN (-2350 4550);
DISPLAY INVISIBLE (-2350 4550);
FORCEPROP 2 LAST CDS_LIB mstr_standard
J 0
(-2675 4675);
DISPLAY 0.723404 (-2675 4675);
PAINT MONO (-2675 4675);
DISPLAY INVISIBLE (-2675 4675);
FORCEADD TAP..1
(-3475 4625);
FORCEPROP 3 LASTPIN (-3525 4625) SIG_NAME M_E_CPU0_SA_DQS_DN<9>
J 0
(-3515 4635);
DISPLAY 0.659574 (-3515 4635);
PAINT MONO (-3515 4635);
DISPLAY INVISIBLE (-3515 4635);
FORCEPROP 1 LASTPIN (-3525 4625) BN 9
J 0
(-3537 4633);
DISPLAY 0.489362 (-3537 4633);
PAINT GREEN (-3537 4633);
FORCEPROP 2 LAST CDS_LIB mstr_standard
J 0
(-3475 4625);
DISPLAY 0.723404 (-3475 4625);
PAINT MONO (-3475 4625);
DISPLAY INVISIBLE (-3475 4625);
FORCEPROP 1 LAST BODY_TYPE PLUMBING
J 0
(-3475 4675);
DISPLAY 0.872340 (-3475 4675);
PAINT GREEN (-3475 4675);
DISPLAY INVISIBLE (-3475 4675);
FORCEPROP 1 LAST HDL_TAP TRUE
J 0
(-3150 4500);
DISPLAY 0.872340 (-3150 4500);
DISPLAY INVISIBLE (-3150 4500);
FORCEPROP 1 LAST PATH I368
J 0
(-3477 4625);
DISPLAY 0.872340 (-3477 4625);
PAINT GREEN (-3477 4625);
DISPLAY INVISIBLE (-3477 4625);
FORCEADD TAP..1
(-3675 4575);
FORCEPROP 3 LASTPIN (-3725 4575) SIG_NAME M_E_CPU0_SA_DQS_DP<8>
J 0
(-3715 4585);
DISPLAY 0.659574 (-3715 4585);
PAINT MONO (-3715 4585);
DISPLAY INVISIBLE (-3715 4585);
FORCEPROP 1 LASTPIN (-3725 4575) BN 8
J 0
(-3737 4583);
DISPLAY 0.489362 (-3737 4583);
PAINT GREEN (-3737 4583);
FORCEPROP 2 LAST CDS_LIB mstr_standard
J 0
(-3675 4575);
DISPLAY 0.723404 (-3675 4575);
PAINT MONO (-3675 4575);
DISPLAY INVISIBLE (-3675 4575);
FORCEPROP 1 LAST BODY_TYPE PLUMBING
J 0
(-3675 4625);
DISPLAY 0.872340 (-3675 4625);
PAINT GREEN (-3675 4625);
DISPLAY INVISIBLE (-3675 4625);
FORCEPROP 1 LAST HDL_TAP TRUE
J 0
(-3350 4450);
DISPLAY 0.872340 (-3350 4450);
DISPLAY INVISIBLE (-3350 4450);
FORCEPROP 1 LAST PATH I369
J 0
(-3677 4575);
DISPLAY 0.872340 (-3677 4575);
PAINT GREEN (-3677 4575);
DISPLAY INVISIBLE (-3677 4575);
FORCEADD TAP..1
(-3675 4675);
FORCEPROP 3 LASTPIN (-3725 4675) SIG_NAME M_E_CPU0_SA_DQS_DP<9>
J 0
(-3715 4685);
DISPLAY 0.659574 (-3715 4685);
PAINT MONO (-3715 4685);
DISPLAY INVISIBLE (-3715 4685);
FORCEPROP 1 LASTPIN (-3725 4675) BN 9
J 0
(-3737 4683);
DISPLAY 0.489362 (-3737 4683);
PAINT GREEN (-3737 4683);
FORCEPROP 2 LAST CDS_LIB mstr_standard
J 0
(-3675 4675);
DISPLAY 0.723404 (-3675 4675);
PAINT MONO (-3675 4675);
DISPLAY INVISIBLE (-3675 4675);
FORCEPROP 1 LAST BODY_TYPE PLUMBING
J 0
(-3675 4725);
DISPLAY 0.872340 (-3675 4725);
PAINT GREEN (-3675 4725);
DISPLAY INVISIBLE (-3675 4725);
FORCEPROP 1 LAST HDL_TAP TRUE
J 0
(-3350 4550);
DISPLAY 0.872340 (-3350 4550);
DISPLAY INVISIBLE (-3350 4550);
FORCEPROP 1 LAST PATH I370
J 0
(-3677 4675);
DISPLAY 0.872340 (-3677 4675);
PAINT GREEN (-3677 4675);
DISPLAY INVISIBLE (-3677 4675);
FORCEADD TAP..1
(-3475 4525);
FORCEPROP 3 LASTPIN (-3525 4525) SIG_NAME M_E_CPU0_SA_DQS_DN<8>
J 0
(-3515 4535);
DISPLAY 0.659574 (-3515 4535);
PAINT MONO (-3515 4535);
DISPLAY INVISIBLE (-3515 4535);
FORCEPROP 1 LASTPIN (-3525 4525) BN 8
J 0
(-3537 4533);
DISPLAY 0.489362 (-3537 4533);
PAINT GREEN (-3537 4533);
FORCEPROP 2 LAST CDS_LIB mstr_standard
J 0
(-3475 4525);
DISPLAY 0.723404 (-3475 4525);
PAINT MONO (-3475 4525);
DISPLAY INVISIBLE (-3475 4525);
FORCEPROP 1 LAST BODY_TYPE PLUMBING
J 0
(-3475 4575);
DISPLAY 0.872340 (-3475 4575);
PAINT GREEN (-3475 4575);
DISPLAY INVISIBLE (-3475 4575);
FORCEPROP 1 LAST HDL_TAP TRUE
J 0
(-3150 4400);
DISPLAY 0.872340 (-3150 4400);
DISPLAY INVISIBLE (-3150 4400);
FORCEPROP 1 LAST PATH I371
J 0
(-3477 4525);
DISPLAY 0.872340 (-3477 4525);
PAINT GREEN (-3477 4525);
DISPLAY INVISIBLE (-3477 4525);
FORCEADD TAP..1
(-3475 4325);
FORCEPROP 3 LASTPIN (-3525 4325) SIG_NAME M_E_CPU0_SA_DQS_DN<6>
J 0
(-3515 4335);
DISPLAY 0.659574 (-3515 4335);
PAINT MONO (-3515 4335);
DISPLAY INVISIBLE (-3515 4335);
FORCEPROP 1 LASTPIN (-3525 4325) BN 6
J 0
(-3537 4333);
DISPLAY 0.489362 (-3537 4333);
PAINT GREEN (-3537 4333);
FORCEPROP 2 LAST CDS_LIB mstr_standard
J 0
(-3475 4325);
DISPLAY 0.723404 (-3475 4325);
PAINT MONO (-3475 4325);
DISPLAY INVISIBLE (-3475 4325);
FORCEPROP 1 LAST BODY_TYPE PLUMBING
J 0
(-3475 4375);
DISPLAY 0.872340 (-3475 4375);
PAINT GREEN (-3475 4375);
DISPLAY INVISIBLE (-3475 4375);
FORCEPROP 1 LAST HDL_TAP TRUE
J 0
(-3150 4200);
DISPLAY 0.872340 (-3150 4200);
DISPLAY INVISIBLE (-3150 4200);
FORCEPROP 1 LAST PATH I372
J 0
(-3477 4325);
DISPLAY 0.872340 (-3477 4325);
PAINT GREEN (-3477 4325);
DISPLAY INVISIBLE (-3477 4325);
FORCEADD TAP..1
(-3475 4425);
FORCEPROP 3 LASTPIN (-3525 4425) SIG_NAME M_E_CPU0_SA_DQS_DN<7>
J 0
(-3515 4435);
DISPLAY 0.659574 (-3515 4435);
PAINT MONO (-3515 4435);
DISPLAY INVISIBLE (-3515 4435);
FORCEPROP 1 LASTPIN (-3525 4425) BN 7
J 0
(-3537 4433);
DISPLAY 0.489362 (-3537 4433);
PAINT GREEN (-3537 4433);
FORCEPROP 2 LAST CDS_LIB mstr_standard
J 0
(-3475 4425);
DISPLAY 0.723404 (-3475 4425);
PAINT MONO (-3475 4425);
DISPLAY INVISIBLE (-3475 4425);
FORCEPROP 1 LAST BODY_TYPE PLUMBING
J 0
(-3475 4475);
DISPLAY 0.872340 (-3475 4475);
PAINT GREEN (-3475 4475);
DISPLAY INVISIBLE (-3475 4475);
FORCEPROP 1 LAST HDL_TAP TRUE
J 0
(-3150 4300);
DISPLAY 0.872340 (-3150 4300);
DISPLAY INVISIBLE (-3150 4300);
FORCEPROP 1 LAST PATH I373
J 0
(-3477 4425);
DISPLAY 0.872340 (-3477 4425);
PAINT GREEN (-3477 4425);
DISPLAY INVISIBLE (-3477 4425);
FORCEADD TAP..1
(-3675 4475);
FORCEPROP 3 LASTPIN (-3725 4475) SIG_NAME M_E_CPU0_SA_DQS_DP<7>
J 0
(-3715 4485);
DISPLAY 0.659574 (-3715 4485);
PAINT MONO (-3715 4485);
DISPLAY INVISIBLE (-3715 4485);
FORCEPROP 1 LASTPIN (-3725 4475) BN 7
J 0
(-3737 4483);
DISPLAY 0.489362 (-3737 4483);
PAINT GREEN (-3737 4483);
FORCEPROP 2 LAST CDS_LIB mstr_standard
J 0
(-3675 4475);
DISPLAY 0.723404 (-3675 4475);
PAINT MONO (-3675 4475);
DISPLAY INVISIBLE (-3675 4475);
FORCEPROP 1 LAST BODY_TYPE PLUMBING
J 0
(-3675 4525);
DISPLAY 0.872340 (-3675 4525);
PAINT GREEN (-3675 4525);
DISPLAY INVISIBLE (-3675 4525);
FORCEPROP 1 LAST HDL_TAP TRUE
J 0
(-3350 4350);
DISPLAY 0.872340 (-3350 4350);
DISPLAY INVISIBLE (-3350 4350);
FORCEPROP 1 LAST PATH I374
J 0
(-3677 4475);
DISPLAY 0.872340 (-3677 4475);
PAINT GREEN (-3677 4475);
DISPLAY INVISIBLE (-3677 4475);
FORCEADD TAP..1
(-3675 4375);
FORCEPROP 3 LASTPIN (-3725 4375) SIG_NAME M_E_CPU0_SA_DQS_DP<6>
J 0
(-3715 4385);
DISPLAY 0.659574 (-3715 4385);
PAINT MONO (-3715 4385);
DISPLAY INVISIBLE (-3715 4385);
FORCEPROP 1 LASTPIN (-3725 4375) BN 6
J 0
(-3737 4383);
DISPLAY 0.489362 (-3737 4383);
PAINT GREEN (-3737 4383);
FORCEPROP 2 LAST CDS_LIB mstr_standard
J 0
(-3675 4375);
DISPLAY 0.723404 (-3675 4375);
PAINT MONO (-3675 4375);
DISPLAY INVISIBLE (-3675 4375);
FORCEPROP 1 LAST BODY_TYPE PLUMBING
J 0
(-3675 4425);
DISPLAY 0.872340 (-3675 4425);
PAINT GREEN (-3675 4425);
DISPLAY INVISIBLE (-3675 4425);
FORCEPROP 1 LAST HDL_TAP TRUE
J 0
(-3350 4250);
DISPLAY 0.872340 (-3350 4250);
DISPLAY INVISIBLE (-3350 4250);
FORCEPROP 1 LAST PATH I375
J 0
(-3677 4375);
DISPLAY 0.872340 (-3677 4375);
PAINT GREEN (-3677 4375);
DISPLAY INVISIBLE (-3677 4375);
FORCEADD OFFPAGE..2
(-2675 3625);
FORCEPROP 2 LAST $XR0 14 
J 0
(-2486 3625);
DISPLAY 0.638298 (-2486 3625);
PAINT MONO (-2486 3625);
FORCEPROP 2 LAST PATH I376
J 0
(-2475 3675);
DISPLAY 0.680851 (-2475 3675);
DISPLAY INVISIBLE (-2475 3675);
FORCEPROP 1 LAST COMMENT_BODY TRUE
J 0
(-2720 3530);
DISPLAY 0.872340 (-2720 3530);
PAINT GREEN (-2720 3530);
DISPLAY INVISIBLE (-2720 3530);
FORCEPROP 1 LAST OFFPAGE TRUE
J 0
(-2350 3500);
DISPLAY 0.723404 (-2350 3500);
PAINT GREEN (-2350 3500);
DISPLAY INVISIBLE (-2350 3500);
FORCEPROP 2 LAST CDS_LIB mstr_standard
J 0
(-2675 3625);
DISPLAY 0.723404 (-2675 3625);
PAINT MONO (-2675 3625);
DISPLAY INVISIBLE (-2675 3625);
FORCEADD OFFPAGE..2
(-2675 3675);
FORCEPROP 2 LAST $XR0 14 
J 0
(-2486 3675);
DISPLAY 0.638298 (-2486 3675);
PAINT MONO (-2486 3675);
FORCEPROP 2 LAST PATH I377
J 0
(-2475 3725);
DISPLAY 0.680851 (-2475 3725);
DISPLAY INVISIBLE (-2475 3725);
FORCEPROP 1 LAST COMMENT_BODY TRUE
J 0
(-2720 3580);
DISPLAY 0.872340 (-2720 3580);
PAINT GREEN (-2720 3580);
DISPLAY INVISIBLE (-2720 3580);
FORCEPROP 1 LAST OFFPAGE TRUE
J 0
(-2350 3550);
DISPLAY 0.723404 (-2350 3550);
PAINT GREEN (-2350 3550);
DISPLAY INVISIBLE (-2350 3550);
FORCEPROP 2 LAST CDS_LIB mstr_standard
J 0
(-2675 3675);
DISPLAY 0.723404 (-2675 3675);
PAINT MONO (-2675 3675);
DISPLAY INVISIBLE (-2675 3675);
FORCEADD TAP..1
(-3475 4125);
FORCEPROP 3 LASTPIN (-3525 4125) SIG_NAME M_E_CPU0_SA_DQS_DN<4>
J 0
(-3515 4135);
DISPLAY 0.659574 (-3515 4135);
PAINT MONO (-3515 4135);
DISPLAY INVISIBLE (-3515 4135);
FORCEPROP 1 LASTPIN (-3525 4125) BN 4
J 0
(-3537 4133);
DISPLAY 0.489362 (-3537 4133);
PAINT GREEN (-3537 4133);
FORCEPROP 2 LAST CDS_LIB mstr_standard
J 0
(-3475 4125);
DISPLAY 0.723404 (-3475 4125);
PAINT MONO (-3475 4125);
DISPLAY INVISIBLE (-3475 4125);
FORCEPROP 1 LAST BODY_TYPE PLUMBING
J 0
(-3475 4175);
DISPLAY 0.872340 (-3475 4175);
PAINT GREEN (-3475 4175);
DISPLAY INVISIBLE (-3475 4175);
FORCEPROP 1 LAST HDL_TAP TRUE
J 0
(-3150 4000);
DISPLAY 0.872340 (-3150 4000);
DISPLAY INVISIBLE (-3150 4000);
FORCEPROP 1 LAST PATH I378
J 0
(-3477 4125);
DISPLAY 0.872340 (-3477 4125);
PAINT GREEN (-3477 4125);
DISPLAY INVISIBLE (-3477 4125);
FORCEADD TAP..1
(-3475 4225);
FORCEPROP 3 LASTPIN (-3525 4225) SIG_NAME M_E_CPU0_SA_DQS_DN<5>
J 0
(-3515 4235);
DISPLAY 0.659574 (-3515 4235);
PAINT MONO (-3515 4235);
DISPLAY INVISIBLE (-3515 4235);
FORCEPROP 1 LASTPIN (-3525 4225) BN 5
J 0
(-3537 4233);
DISPLAY 0.489362 (-3537 4233);
PAINT GREEN (-3537 4233);
FORCEPROP 2 LAST CDS_LIB mstr_standard
J 0
(-3475 4225);
DISPLAY 0.723404 (-3475 4225);
PAINT MONO (-3475 4225);
DISPLAY INVISIBLE (-3475 4225);
FORCEPROP 1 LAST BODY_TYPE PLUMBING
J 0
(-3475 4275);
DISPLAY 0.872340 (-3475 4275);
PAINT GREEN (-3475 4275);
DISPLAY INVISIBLE (-3475 4275);
FORCEPROP 1 LAST HDL_TAP TRUE
J 0
(-3150 4100);
DISPLAY 0.872340 (-3150 4100);
DISPLAY INVISIBLE (-3150 4100);
FORCEPROP 1 LAST PATH I379
J 0
(-3477 4225);
DISPLAY 0.872340 (-3477 4225);
PAINT GREEN (-3477 4225);
DISPLAY INVISIBLE (-3477 4225);
FORCEADD TAP..1
(-3675 4175);
FORCEPROP 3 LASTPIN (-3725 4175) SIG_NAME M_E_CPU0_SA_DQS_DP<4>
J 0
(-3715 4185);
DISPLAY 0.659574 (-3715 4185);
PAINT MONO (-3715 4185);
DISPLAY INVISIBLE (-3715 4185);
FORCEPROP 1 LASTPIN (-3725 4175) BN 4
J 0
(-3737 4183);
DISPLAY 0.489362 (-3737 4183);
PAINT GREEN (-3737 4183);
FORCEPROP 2 LAST CDS_LIB mstr_standard
J 0
(-3675 4175);
DISPLAY 0.723404 (-3675 4175);
PAINT MONO (-3675 4175);
DISPLAY INVISIBLE (-3675 4175);
FORCEPROP 1 LAST BODY_TYPE PLUMBING
J 0
(-3675 4225);
DISPLAY 0.872340 (-3675 4225);
PAINT GREEN (-3675 4225);
DISPLAY INVISIBLE (-3675 4225);
FORCEPROP 1 LAST HDL_TAP TRUE
J 0
(-3350 4050);
DISPLAY 0.872340 (-3350 4050);
DISPLAY INVISIBLE (-3350 4050);
FORCEPROP 1 LAST PATH I380
J 0
(-3677 4175);
DISPLAY 0.872340 (-3677 4175);
PAINT GREEN (-3677 4175);
DISPLAY INVISIBLE (-3677 4175);
FORCEADD TAP..1
(-3675 4275);
FORCEPROP 3 LASTPIN (-3725 4275) SIG_NAME M_E_CPU0_SA_DQS_DP<5>
J 0
(-3715 4285);
DISPLAY 0.659574 (-3715 4285);
PAINT MONO (-3715 4285);
DISPLAY INVISIBLE (-3715 4285);
FORCEPROP 1 LASTPIN (-3725 4275) BN 5
J 0
(-3737 4283);
DISPLAY 0.489362 (-3737 4283);
PAINT GREEN (-3737 4283);
FORCEPROP 2 LAST CDS_LIB mstr_standard
J 0
(-3675 4275);
DISPLAY 0.723404 (-3675 4275);
PAINT MONO (-3675 4275);
DISPLAY INVISIBLE (-3675 4275);
FORCEPROP 1 LAST BODY_TYPE PLUMBING
J 0
(-3675 4325);
DISPLAY 0.872340 (-3675 4325);
PAINT GREEN (-3675 4325);
DISPLAY INVISIBLE (-3675 4325);
FORCEPROP 1 LAST HDL_TAP TRUE
J 0
(-3350 4150);
DISPLAY 0.872340 (-3350 4150);
DISPLAY INVISIBLE (-3350 4150);
FORCEPROP 1 LAST PATH I381
J 0
(-3677 4275);
DISPLAY 0.872340 (-3677 4275);
PAINT GREEN (-3677 4275);
DISPLAY INVISIBLE (-3677 4275);
FORCEADD TAP..1
(-3675 4075);
FORCEPROP 3 LASTPIN (-3725 4075) SIG_NAME M_E_CPU0_SA_DQS_DP<3>
J 0
(-3715 4085);
DISPLAY 0.659574 (-3715 4085);
PAINT MONO (-3715 4085);
DISPLAY INVISIBLE (-3715 4085);
FORCEPROP 1 LASTPIN (-3725 4075) BN 3
J 0
(-3737 4083);
DISPLAY 0.489362 (-3737 4083);
PAINT GREEN (-3737 4083);
FORCEPROP 2 LAST CDS_LIB mstr_standard
J 0
(-3675 4075);
DISPLAY 0.723404 (-3675 4075);
PAINT MONO (-3675 4075);
DISPLAY INVISIBLE (-3675 4075);
FORCEPROP 1 LAST BODY_TYPE PLUMBING
J 0
(-3675 4125);
DISPLAY 0.872340 (-3675 4125);
PAINT GREEN (-3675 4125);
DISPLAY INVISIBLE (-3675 4125);
FORCEPROP 1 LAST HDL_TAP TRUE
J 0
(-3350 3950);
DISPLAY 0.872340 (-3350 3950);
DISPLAY INVISIBLE (-3350 3950);
FORCEPROP 1 LAST PATH I382
J 0
(-3677 4075);
DISPLAY 0.872340 (-3677 4075);
PAINT GREEN (-3677 4075);
DISPLAY INVISIBLE (-3677 4075);
FORCEADD TAP..1
(-3475 3925);
FORCEPROP 3 LASTPIN (-3525 3925) SIG_NAME M_E_CPU0_SA_DQS_DN<2>
J 0
(-3515 3935);
DISPLAY 0.659574 (-3515 3935);
PAINT MONO (-3515 3935);
DISPLAY INVISIBLE (-3515 3935);
FORCEPROP 1 LASTPIN (-3525 3925) BN 2
J 0
(-3537 3933);
DISPLAY 0.489362 (-3537 3933);
PAINT GREEN (-3537 3933);
FORCEPROP 2 LAST CDS_LIB mstr_standard
J 0
(-3475 3925);
DISPLAY 0.723404 (-3475 3925);
PAINT MONO (-3475 3925);
DISPLAY INVISIBLE (-3475 3925);
FORCEPROP 1 LAST BODY_TYPE PLUMBING
J 0
(-3475 3975);
DISPLAY 0.872340 (-3475 3975);
PAINT GREEN (-3475 3975);
DISPLAY INVISIBLE (-3475 3975);
FORCEPROP 1 LAST HDL_TAP TRUE
J 0
(-3150 3800);
DISPLAY 0.872340 (-3150 3800);
DISPLAY INVISIBLE (-3150 3800);
FORCEPROP 1 LAST PATH I383
J 0
(-3477 3925);
DISPLAY 0.872340 (-3477 3925);
PAINT GREEN (-3477 3925);
DISPLAY INVISIBLE (-3477 3925);
FORCEADD TAP..1
(-3475 4025);
FORCEPROP 3 LASTPIN (-3525 4025) SIG_NAME M_E_CPU0_SA_DQS_DN<3>
J 0
(-3515 4035);
DISPLAY 0.659574 (-3515 4035);
PAINT MONO (-3515 4035);
DISPLAY INVISIBLE (-3515 4035);
FORCEPROP 1 LASTPIN (-3525 4025) BN 3
J 0
(-3537 4033);
DISPLAY 0.489362 (-3537 4033);
PAINT GREEN (-3537 4033);
FORCEPROP 2 LAST CDS_LIB mstr_standard
J 0
(-3475 4025);
DISPLAY 0.723404 (-3475 4025);
PAINT MONO (-3475 4025);
DISPLAY INVISIBLE (-3475 4025);
FORCEPROP 1 LAST BODY_TYPE PLUMBING
J 0
(-3475 4075);
DISPLAY 0.872340 (-3475 4075);
PAINT GREEN (-3475 4075);
DISPLAY INVISIBLE (-3475 4075);
FORCEPROP 1 LAST HDL_TAP TRUE
J 0
(-3150 3900);
DISPLAY 0.872340 (-3150 3900);
DISPLAY INVISIBLE (-3150 3900);
FORCEPROP 1 LAST PATH I384
J 0
(-3477 4025);
DISPLAY 0.872340 (-3477 4025);
PAINT GREEN (-3477 4025);
DISPLAY INVISIBLE (-3477 4025);
FORCEADD TAP..1
(-3475 3825);
FORCEPROP 3 LASTPIN (-3525 3825) SIG_NAME M_E_CPU0_SA_DQS_DN<1>
J 0
(-3515 3835);
DISPLAY 0.659574 (-3515 3835);
PAINT MONO (-3515 3835);
DISPLAY INVISIBLE (-3515 3835);
FORCEPROP 1 LASTPIN (-3525 3825) BN 1
J 0
(-3537 3833);
DISPLAY 0.489362 (-3537 3833);
PAINT GREEN (-3537 3833);
FORCEPROP 2 LAST CDS_LIB mstr_standard
J 0
(-3475 3825);
DISPLAY 0.723404 (-3475 3825);
PAINT MONO (-3475 3825);
DISPLAY INVISIBLE (-3475 3825);
FORCEPROP 1 LAST BODY_TYPE PLUMBING
J 0
(-3475 3875);
DISPLAY 0.872340 (-3475 3875);
PAINT GREEN (-3475 3875);
DISPLAY INVISIBLE (-3475 3875);
FORCEPROP 1 LAST HDL_TAP TRUE
J 0
(-3150 3700);
DISPLAY 0.872340 (-3150 3700);
DISPLAY INVISIBLE (-3150 3700);
FORCEPROP 1 LAST PATH I385
J 0
(-3477 3825);
DISPLAY 0.872340 (-3477 3825);
PAINT GREEN (-3477 3825);
DISPLAY INVISIBLE (-3477 3825);
FORCEADD TAP..1
(-3675 3975);
FORCEPROP 3 LASTPIN (-3725 3975) SIG_NAME M_E_CPU0_SA_DQS_DP<2>
J 0
(-3715 3985);
DISPLAY 0.659574 (-3715 3985);
PAINT MONO (-3715 3985);
DISPLAY INVISIBLE (-3715 3985);
FORCEPROP 1 LASTPIN (-3725 3975) BN 2
J 0
(-3737 3983);
DISPLAY 0.489362 (-3737 3983);
PAINT GREEN (-3737 3983);
FORCEPROP 2 LAST CDS_LIB mstr_standard
J 0
(-3675 3975);
DISPLAY 0.723404 (-3675 3975);
PAINT MONO (-3675 3975);
DISPLAY INVISIBLE (-3675 3975);
FORCEPROP 1 LAST BODY_TYPE PLUMBING
J 0
(-3675 4025);
DISPLAY 0.872340 (-3675 4025);
PAINT GREEN (-3675 4025);
DISPLAY INVISIBLE (-3675 4025);
FORCEPROP 1 LAST HDL_TAP TRUE
J 0
(-3350 3850);
DISPLAY 0.872340 (-3350 3850);
DISPLAY INVISIBLE (-3350 3850);
FORCEPROP 1 LAST PATH I386
J 0
(-3677 3975);
DISPLAY 0.872340 (-3677 3975);
PAINT GREEN (-3677 3975);
DISPLAY INVISIBLE (-3677 3975);
FORCEADD TAP..1
(-3675 3875);
FORCEPROP 3 LASTPIN (-3725 3875) SIG_NAME M_E_CPU0_SA_DQS_DP<1>
J 0
(-3715 3885);
DISPLAY 0.659574 (-3715 3885);
PAINT MONO (-3715 3885);
DISPLAY INVISIBLE (-3715 3885);
FORCEPROP 1 LASTPIN (-3725 3875) BN 1
J 0
(-3737 3883);
DISPLAY 0.489362 (-3737 3883);
PAINT GREEN (-3737 3883);
FORCEPROP 2 LAST CDS_LIB mstr_standard
J 0
(-3675 3875);
DISPLAY 0.723404 (-3675 3875);
PAINT MONO (-3675 3875);
DISPLAY INVISIBLE (-3675 3875);
FORCEPROP 1 LAST BODY_TYPE PLUMBING
J 0
(-3675 3925);
DISPLAY 0.872340 (-3675 3925);
PAINT GREEN (-3675 3925);
DISPLAY INVISIBLE (-3675 3925);
FORCEPROP 1 LAST HDL_TAP TRUE
J 0
(-3350 3750);
DISPLAY 0.872340 (-3350 3750);
DISPLAY INVISIBLE (-3350 3750);
FORCEPROP 1 LAST PATH I387
J 0
(-3677 3875);
DISPLAY 0.872340 (-3677 3875);
PAINT GREEN (-3677 3875);
DISPLAY INVISIBLE (-3677 3875);
FORCEADD TAP..1
(-3475 3575);
FORCEPROP 3 LASTPIN (-3525 3575) SIG_NAME M_E_CPU0_SB_DQS_DN<9>
J 0
(-3515 3585);
DISPLAY 0.659574 (-3515 3585);
PAINT MONO (-3515 3585);
DISPLAY INVISIBLE (-3515 3585);
FORCEPROP 1 LASTPIN (-3525 3575) BN 9
J 0
(-3537 3583);
DISPLAY 0.489362 (-3537 3583);
PAINT GREEN (-3537 3583);
FORCEPROP 2 LAST CDS_LIB mstr_standard
J 0
(-3475 3575);
DISPLAY 0.723404 (-3475 3575);
PAINT MONO (-3475 3575);
DISPLAY INVISIBLE (-3475 3575);
FORCEPROP 1 LAST BODY_TYPE PLUMBING
J 0
(-3475 3625);
DISPLAY 0.872340 (-3475 3625);
PAINT GREEN (-3475 3625);
DISPLAY INVISIBLE (-3475 3625);
FORCEPROP 1 LAST HDL_TAP TRUE
J 0
(-3150 3450);
DISPLAY 0.872340 (-3150 3450);
DISPLAY INVISIBLE (-3150 3450);
FORCEPROP 1 LAST PATH I388
J 0
(-3477 3575);
DISPLAY 0.872340 (-3477 3575);
PAINT GREEN (-3477 3575);
DISPLAY INVISIBLE (-3477 3575);
FORCEADD TAP..1
(-3475 3725);
FORCEPROP 3 LASTPIN (-3525 3725) SIG_NAME M_E_CPU0_SA_DQS_DN<0>
J 0
(-3515 3735);
DISPLAY 0.659574 (-3515 3735);
PAINT MONO (-3515 3735);
DISPLAY INVISIBLE (-3515 3735);
FORCEPROP 1 LASTPIN (-3525 3725) BN 0
J 0
(-3537 3733);
DISPLAY 0.489362 (-3537 3733);
PAINT GREEN (-3537 3733);
FORCEPROP 2 LAST CDS_LIB mstr_standard
J 0
(-3475 3725);
DISPLAY 0.723404 (-3475 3725);
PAINT MONO (-3475 3725);
DISPLAY INVISIBLE (-3475 3725);
FORCEPROP 1 LAST BODY_TYPE PLUMBING
J 0
(-3475 3775);
DISPLAY 0.872340 (-3475 3775);
PAINT GREEN (-3475 3775);
DISPLAY INVISIBLE (-3475 3775);
FORCEPROP 1 LAST HDL_TAP TRUE
J 0
(-3150 3600);
DISPLAY 0.872340 (-3150 3600);
DISPLAY INVISIBLE (-3150 3600);
FORCEPROP 1 LAST PATH I389
J 0
(-3477 3725);
DISPLAY 0.872340 (-3477 3725);
PAINT GREEN (-3477 3725);
DISPLAY INVISIBLE (-3477 3725);
FORCEADD TAP..1
(-3675 3775);
FORCEPROP 3 LASTPIN (-3725 3775) SIG_NAME M_E_CPU0_SA_DQS_DP<0>
J 0
(-3715 3785);
DISPLAY 0.659574 (-3715 3785);
PAINT MONO (-3715 3785);
DISPLAY INVISIBLE (-3715 3785);
FORCEPROP 1 LASTPIN (-3725 3775) BN 0
J 0
(-3737 3783);
DISPLAY 0.489362 (-3737 3783);
PAINT GREEN (-3737 3783);
FORCEPROP 2 LAST CDS_LIB mstr_standard
J 0
(-3675 3775);
DISPLAY 0.723404 (-3675 3775);
PAINT MONO (-3675 3775);
DISPLAY INVISIBLE (-3675 3775);
FORCEPROP 1 LAST BODY_TYPE PLUMBING
J 0
(-3675 3825);
DISPLAY 0.872340 (-3675 3825);
PAINT GREEN (-3675 3825);
DISPLAY INVISIBLE (-3675 3825);
FORCEPROP 1 LAST HDL_TAP TRUE
J 0
(-3350 3650);
DISPLAY 0.872340 (-3350 3650);
DISPLAY INVISIBLE (-3350 3650);
FORCEPROP 1 LAST PATH I390
J 0
(-3677 3775);
DISPLAY 0.872340 (-3677 3775);
PAINT GREEN (-3677 3775);
DISPLAY INVISIBLE (-3677 3775);
FORCEADD TAP..1
(-3675 3625);
FORCEPROP 3 LASTPIN (-3725 3625) SIG_NAME M_E_CPU0_SB_DQS_DP<9>
J 0
(-3715 3635);
DISPLAY 0.659574 (-3715 3635);
PAINT MONO (-3715 3635);
DISPLAY INVISIBLE (-3715 3635);
FORCEPROP 1 LASTPIN (-3725 3625) BN 9
J 0
(-3737 3633);
DISPLAY 0.489362 (-3737 3633);
PAINT GREEN (-3737 3633);
FORCEPROP 2 LAST CDS_LIB mstr_standard
J 0
(-3675 3625);
DISPLAY 0.723404 (-3675 3625);
PAINT MONO (-3675 3625);
DISPLAY INVISIBLE (-3675 3625);
FORCEPROP 1 LAST BODY_TYPE PLUMBING
J 0
(-3675 3675);
DISPLAY 0.872340 (-3675 3675);
PAINT GREEN (-3675 3675);
DISPLAY INVISIBLE (-3675 3675);
FORCEPROP 1 LAST HDL_TAP TRUE
J 0
(-3350 3500);
DISPLAY 0.872340 (-3350 3500);
DISPLAY INVISIBLE (-3350 3500);
FORCEPROP 1 LAST PATH I391
J 0
(-3677 3625);
DISPLAY 0.872340 (-3677 3625);
PAINT GREEN (-3677 3625);
DISPLAY INVISIBLE (-3677 3625);
FORCEADD TAP..1
(-3475 3475);
FORCEPROP 3 LASTPIN (-3525 3475) SIG_NAME M_E_CPU0_SB_DQS_DN<8>
J 0
(-3515 3485);
DISPLAY 0.659574 (-3515 3485);
PAINT MONO (-3515 3485);
DISPLAY INVISIBLE (-3515 3485);
FORCEPROP 1 LASTPIN (-3525 3475) BN 8
J 0
(-3537 3483);
DISPLAY 0.489362 (-3537 3483);
PAINT GREEN (-3537 3483);
FORCEPROP 2 LAST CDS_LIB mstr_standard
J 0
(-3475 3475);
DISPLAY 0.723404 (-3475 3475);
PAINT MONO (-3475 3475);
DISPLAY INVISIBLE (-3475 3475);
FORCEPROP 1 LAST BODY_TYPE PLUMBING
J 0
(-3475 3525);
DISPLAY 0.872340 (-3475 3525);
PAINT GREEN (-3475 3525);
DISPLAY INVISIBLE (-3475 3525);
FORCEPROP 1 LAST HDL_TAP TRUE
J 0
(-3150 3350);
DISPLAY 0.872340 (-3150 3350);
DISPLAY INVISIBLE (-3150 3350);
FORCEPROP 1 LAST PATH I392
J 0
(-3477 3475);
DISPLAY 0.872340 (-3477 3475);
PAINT GREEN (-3477 3475);
DISPLAY INVISIBLE (-3477 3475);
FORCEADD TAP..1
(-3475 3275);
FORCEPROP 3 LASTPIN (-3525 3275) SIG_NAME M_E_CPU0_SB_DQS_DN<6>
J 0
(-3515 3285);
DISPLAY 0.659574 (-3515 3285);
PAINT MONO (-3515 3285);
DISPLAY INVISIBLE (-3515 3285);
FORCEPROP 1 LASTPIN (-3525 3275) BN 6
J 0
(-3537 3283);
DISPLAY 0.489362 (-3537 3283);
PAINT GREEN (-3537 3283);
FORCEPROP 2 LAST CDS_LIB mstr_standard
J 0
(-3475 3275);
DISPLAY 0.723404 (-3475 3275);
PAINT MONO (-3475 3275);
DISPLAY INVISIBLE (-3475 3275);
FORCEPROP 1 LAST BODY_TYPE PLUMBING
J 0
(-3475 3325);
DISPLAY 0.872340 (-3475 3325);
PAINT GREEN (-3475 3325);
DISPLAY INVISIBLE (-3475 3325);
FORCEPROP 1 LAST HDL_TAP TRUE
J 0
(-3150 3150);
DISPLAY 0.872340 (-3150 3150);
DISPLAY INVISIBLE (-3150 3150);
FORCEPROP 1 LAST PATH I393
J 0
(-3477 3275);
DISPLAY 0.872340 (-3477 3275);
PAINT GREEN (-3477 3275);
DISPLAY INVISIBLE (-3477 3275);
FORCEADD TAP..1
(-3475 3375);
FORCEPROP 3 LASTPIN (-3525 3375) SIG_NAME M_E_CPU0_SB_DQS_DN<7>
J 0
(-3515 3385);
DISPLAY 0.659574 (-3515 3385);
PAINT MONO (-3515 3385);
DISPLAY INVISIBLE (-3515 3385);
FORCEPROP 1 LASTPIN (-3525 3375) BN 7
J 0
(-3537 3383);
DISPLAY 0.489362 (-3537 3383);
PAINT GREEN (-3537 3383);
FORCEPROP 2 LAST CDS_LIB mstr_standard
J 0
(-3475 3375);
DISPLAY 0.723404 (-3475 3375);
PAINT MONO (-3475 3375);
DISPLAY INVISIBLE (-3475 3375);
FORCEPROP 1 LAST BODY_TYPE PLUMBING
J 0
(-3475 3425);
DISPLAY 0.872340 (-3475 3425);
PAINT GREEN (-3475 3425);
DISPLAY INVISIBLE (-3475 3425);
FORCEPROP 1 LAST HDL_TAP TRUE
J 0
(-3150 3250);
DISPLAY 0.872340 (-3150 3250);
DISPLAY INVISIBLE (-3150 3250);
FORCEPROP 1 LAST PATH I394
J 0
(-3477 3375);
DISPLAY 0.872340 (-3477 3375);
PAINT GREEN (-3477 3375);
DISPLAY INVISIBLE (-3477 3375);
FORCEADD TAP..1
(-3675 3525);
FORCEPROP 3 LASTPIN (-3725 3525) SIG_NAME M_E_CPU0_SB_DQS_DP<8>
J 0
(-3715 3535);
DISPLAY 0.659574 (-3715 3535);
PAINT MONO (-3715 3535);
DISPLAY INVISIBLE (-3715 3535);
FORCEPROP 1 LASTPIN (-3725 3525) BN 8
J 0
(-3737 3533);
DISPLAY 0.489362 (-3737 3533);
PAINT GREEN (-3737 3533);
FORCEPROP 2 LAST CDS_LIB mstr_standard
J 0
(-3675 3525);
DISPLAY 0.723404 (-3675 3525);
PAINT MONO (-3675 3525);
DISPLAY INVISIBLE (-3675 3525);
FORCEPROP 1 LAST BODY_TYPE PLUMBING
J 0
(-3675 3575);
DISPLAY 0.872340 (-3675 3575);
PAINT GREEN (-3675 3575);
DISPLAY INVISIBLE (-3675 3575);
FORCEPROP 1 LAST HDL_TAP TRUE
J 0
(-3350 3400);
DISPLAY 0.872340 (-3350 3400);
DISPLAY INVISIBLE (-3350 3400);
FORCEPROP 1 LAST PATH I395
J 0
(-3677 3525);
DISPLAY 0.872340 (-3677 3525);
PAINT GREEN (-3677 3525);
DISPLAY INVISIBLE (-3677 3525);
FORCEADD TAP..1
(-3675 3425);
FORCEPROP 3 LASTPIN (-3725 3425) SIG_NAME M_E_CPU0_SB_DQS_DP<7>
J 0
(-3715 3435);
DISPLAY 0.659574 (-3715 3435);
PAINT MONO (-3715 3435);
DISPLAY INVISIBLE (-3715 3435);
FORCEPROP 1 LASTPIN (-3725 3425) BN 7
J 0
(-3737 3433);
DISPLAY 0.489362 (-3737 3433);
PAINT GREEN (-3737 3433);
FORCEPROP 2 LAST CDS_LIB mstr_standard
J 0
(-3675 3425);
DISPLAY 0.723404 (-3675 3425);
PAINT MONO (-3675 3425);
DISPLAY INVISIBLE (-3675 3425);
FORCEPROP 1 LAST BODY_TYPE PLUMBING
J 0
(-3675 3475);
DISPLAY 0.872340 (-3675 3475);
PAINT GREEN (-3675 3475);
DISPLAY INVISIBLE (-3675 3475);
FORCEPROP 1 LAST HDL_TAP TRUE
J 0
(-3350 3300);
DISPLAY 0.872340 (-3350 3300);
DISPLAY INVISIBLE (-3350 3300);
FORCEPROP 1 LAST PATH I396
J 0
(-3677 3425);
DISPLAY 0.872340 (-3677 3425);
PAINT GREEN (-3677 3425);
DISPLAY INVISIBLE (-3677 3425);
FORCEADD TAP..1
(-3675 3325);
FORCEPROP 3 LASTPIN (-3725 3325) SIG_NAME M_E_CPU0_SB_DQS_DP<6>
J 0
(-3715 3335);
DISPLAY 0.659574 (-3715 3335);
PAINT MONO (-3715 3335);
DISPLAY INVISIBLE (-3715 3335);
FORCEPROP 1 LASTPIN (-3725 3325) BN 6
J 0
(-3737 3333);
DISPLAY 0.489362 (-3737 3333);
PAINT GREEN (-3737 3333);
FORCEPROP 2 LAST CDS_LIB mstr_standard
J 0
(-3675 3325);
DISPLAY 0.723404 (-3675 3325);
PAINT MONO (-3675 3325);
DISPLAY INVISIBLE (-3675 3325);
FORCEPROP 1 LAST BODY_TYPE PLUMBING
J 0
(-3675 3375);
DISPLAY 0.872340 (-3675 3375);
PAINT GREEN (-3675 3375);
DISPLAY INVISIBLE (-3675 3375);
FORCEPROP 1 LAST HDL_TAP TRUE
J 0
(-3350 3200);
DISPLAY 0.872340 (-3350 3200);
DISPLAY INVISIBLE (-3350 3200);
FORCEPROP 1 LAST PATH I397
J 0
(-3677 3325);
DISPLAY 0.872340 (-3677 3325);
PAINT GREEN (-3677 3325);
DISPLAY INVISIBLE (-3677 3325);
FORCEADD TAP..1
(-3475 3075);
FORCEPROP 3 LASTPIN (-3525 3075) SIG_NAME M_E_CPU0_SB_DQS_DN<4>
J 0
(-3515 3085);
DISPLAY 0.659574 (-3515 3085);
PAINT MONO (-3515 3085);
DISPLAY INVISIBLE (-3515 3085);
FORCEPROP 1 LASTPIN (-3525 3075) BN 4
J 0
(-3537 3083);
DISPLAY 0.489362 (-3537 3083);
PAINT GREEN (-3537 3083);
FORCEPROP 2 LAST CDS_LIB mstr_standard
J 0
(-3475 3075);
DISPLAY 0.723404 (-3475 3075);
PAINT MONO (-3475 3075);
DISPLAY INVISIBLE (-3475 3075);
FORCEPROP 1 LAST BODY_TYPE PLUMBING
J 0
(-3475 3125);
DISPLAY 0.872340 (-3475 3125);
PAINT GREEN (-3475 3125);
DISPLAY INVISIBLE (-3475 3125);
FORCEPROP 1 LAST HDL_TAP TRUE
J 0
(-3150 2950);
DISPLAY 0.872340 (-3150 2950);
DISPLAY INVISIBLE (-3150 2950);
FORCEPROP 1 LAST PATH I398
J 0
(-3477 3075);
DISPLAY 0.872340 (-3477 3075);
PAINT GREEN (-3477 3075);
DISPLAY INVISIBLE (-3477 3075);
FORCEADD TAP..1
(-3475 3175);
FORCEPROP 3 LASTPIN (-3525 3175) SIG_NAME M_E_CPU0_SB_DQS_DN<5>
J 0
(-3515 3185);
DISPLAY 0.659574 (-3515 3185);
PAINT MONO (-3515 3185);
DISPLAY INVISIBLE (-3515 3185);
FORCEPROP 1 LASTPIN (-3525 3175) BN 5
J 0
(-3537 3183);
DISPLAY 0.489362 (-3537 3183);
PAINT GREEN (-3537 3183);
FORCEPROP 2 LAST CDS_LIB mstr_standard
J 0
(-3475 3175);
DISPLAY 0.723404 (-3475 3175);
PAINT MONO (-3475 3175);
DISPLAY INVISIBLE (-3475 3175);
FORCEPROP 1 LAST BODY_TYPE PLUMBING
J 0
(-3475 3225);
DISPLAY 0.872340 (-3475 3225);
PAINT GREEN (-3475 3225);
DISPLAY INVISIBLE (-3475 3225);
FORCEPROP 1 LAST HDL_TAP TRUE
J 0
(-3150 3050);
DISPLAY 0.872340 (-3150 3050);
DISPLAY INVISIBLE (-3150 3050);
FORCEPROP 1 LAST PATH I399
J 0
(-3477 3175);
DISPLAY 0.872340 (-3477 3175);
PAINT GREEN (-3477 3175);
DISPLAY INVISIBLE (-3477 3175);
FORCEADD TAP..1
(-3675 3225);
FORCEPROP 3 LASTPIN (-3725 3225) SIG_NAME M_E_CPU0_SB_DQS_DP<5>
J 0
(-3715 3235);
DISPLAY 0.659574 (-3715 3235);
PAINT MONO (-3715 3235);
DISPLAY INVISIBLE (-3715 3235);
FORCEPROP 1 LASTPIN (-3725 3225) BN 5
J 0
(-3737 3233);
DISPLAY 0.489362 (-3737 3233);
PAINT GREEN (-3737 3233);
FORCEPROP 2 LAST CDS_LIB mstr_standard
J 0
(-3675 3225);
DISPLAY 0.723404 (-3675 3225);
PAINT MONO (-3675 3225);
DISPLAY INVISIBLE (-3675 3225);
FORCEPROP 1 LAST BODY_TYPE PLUMBING
J 0
(-3675 3275);
DISPLAY 0.872340 (-3675 3275);
PAINT GREEN (-3675 3275);
DISPLAY INVISIBLE (-3675 3275);
FORCEPROP 1 LAST HDL_TAP TRUE
J 0
(-3350 3100);
DISPLAY 0.872340 (-3350 3100);
DISPLAY INVISIBLE (-3350 3100);
FORCEPROP 1 LAST PATH I400
J 0
(-3677 3225);
DISPLAY 0.872340 (-3677 3225);
PAINT GREEN (-3677 3225);
DISPLAY INVISIBLE (-3677 3225);
FORCEADD TAP..1
(-3675 3025);
FORCEPROP 3 LASTPIN (-3725 3025) SIG_NAME M_E_CPU0_SB_DQS_DP<3>
J 0
(-3715 3035);
DISPLAY 0.659574 (-3715 3035);
PAINT MONO (-3715 3035);
DISPLAY INVISIBLE (-3715 3035);
FORCEPROP 1 LASTPIN (-3725 3025) BN 3
J 0
(-3737 3033);
DISPLAY 0.489362 (-3737 3033);
PAINT GREEN (-3737 3033);
FORCEPROP 2 LAST CDS_LIB mstr_standard
J 0
(-3675 3025);
DISPLAY 0.723404 (-3675 3025);
PAINT MONO (-3675 3025);
DISPLAY INVISIBLE (-3675 3025);
FORCEPROP 1 LAST BODY_TYPE PLUMBING
J 0
(-3675 3075);
DISPLAY 0.872340 (-3675 3075);
PAINT GREEN (-3675 3075);
DISPLAY INVISIBLE (-3675 3075);
FORCEPROP 1 LAST HDL_TAP TRUE
J 0
(-3350 2900);
DISPLAY 0.872340 (-3350 2900);
DISPLAY INVISIBLE (-3350 2900);
FORCEPROP 1 LAST PATH I401
J 0
(-3677 3025);
DISPLAY 0.872340 (-3677 3025);
PAINT GREEN (-3677 3025);
DISPLAY INVISIBLE (-3677 3025);
FORCEADD TAP..1
(-3675 3125);
FORCEPROP 3 LASTPIN (-3725 3125) SIG_NAME M_E_CPU0_SB_DQS_DP<4>
J 0
(-3715 3135);
DISPLAY 0.659574 (-3715 3135);
PAINT MONO (-3715 3135);
DISPLAY INVISIBLE (-3715 3135);
FORCEPROP 1 LASTPIN (-3725 3125) BN 4
J 0
(-3737 3133);
DISPLAY 0.489362 (-3737 3133);
PAINT GREEN (-3737 3133);
FORCEPROP 2 LAST CDS_LIB mstr_standard
J 0
(-3675 3125);
DISPLAY 0.723404 (-3675 3125);
PAINT MONO (-3675 3125);
DISPLAY INVISIBLE (-3675 3125);
FORCEPROP 1 LAST BODY_TYPE PLUMBING
J 0
(-3675 3175);
DISPLAY 0.872340 (-3675 3175);
PAINT GREEN (-3675 3175);
DISPLAY INVISIBLE (-3675 3175);
FORCEPROP 1 LAST HDL_TAP TRUE
J 0
(-3350 3000);
DISPLAY 0.872340 (-3350 3000);
DISPLAY INVISIBLE (-3350 3000);
FORCEPROP 1 LAST PATH I402
J 0
(-3677 3125);
DISPLAY 0.872340 (-3677 3125);
PAINT GREEN (-3677 3125);
DISPLAY INVISIBLE (-3677 3125);
FORCEADD TAP..1
(-3475 2975);
FORCEPROP 3 LASTPIN (-3525 2975) SIG_NAME M_E_CPU0_SB_DQS_DN<3>
J 0
(-3515 2985);
DISPLAY 0.659574 (-3515 2985);
PAINT MONO (-3515 2985);
DISPLAY INVISIBLE (-3515 2985);
FORCEPROP 1 LASTPIN (-3525 2975) BN 3
J 0
(-3537 2983);
DISPLAY 0.489362 (-3537 2983);
PAINT GREEN (-3537 2983);
FORCEPROP 2 LAST CDS_LIB mstr_standard
J 0
(-3475 2975);
DISPLAY 0.723404 (-3475 2975);
PAINT MONO (-3475 2975);
DISPLAY INVISIBLE (-3475 2975);
FORCEPROP 1 LAST BODY_TYPE PLUMBING
J 0
(-3475 3025);
DISPLAY 0.872340 (-3475 3025);
PAINT GREEN (-3475 3025);
DISPLAY INVISIBLE (-3475 3025);
FORCEPROP 1 LAST HDL_TAP TRUE
J 0
(-3150 2850);
DISPLAY 0.872340 (-3150 2850);
DISPLAY INVISIBLE (-3150 2850);
FORCEPROP 1 LAST PATH I403
J 0
(-3477 2975);
DISPLAY 0.872340 (-3477 2975);
PAINT GREEN (-3477 2975);
DISPLAY INVISIBLE (-3477 2975);
FORCEADD TAP..1
(-3475 2775);
FORCEPROP 3 LASTPIN (-3525 2775) SIG_NAME M_E_CPU0_SB_DQS_DN<1>
J 0
(-3515 2785);
DISPLAY 0.659574 (-3515 2785);
PAINT MONO (-3515 2785);
DISPLAY INVISIBLE (-3515 2785);
FORCEPROP 1 LASTPIN (-3525 2775) BN 1
J 0
(-3537 2783);
DISPLAY 0.489362 (-3537 2783);
PAINT GREEN (-3537 2783);
FORCEPROP 2 LAST CDS_LIB mstr_standard
J 0
(-3475 2775);
DISPLAY 0.723404 (-3475 2775);
PAINT MONO (-3475 2775);
DISPLAY INVISIBLE (-3475 2775);
FORCEPROP 1 LAST BODY_TYPE PLUMBING
J 0
(-3475 2825);
DISPLAY 0.872340 (-3475 2825);
PAINT GREEN (-3475 2825);
DISPLAY INVISIBLE (-3475 2825);
FORCEPROP 1 LAST HDL_TAP TRUE
J 0
(-3150 2650);
DISPLAY 0.872340 (-3150 2650);
DISPLAY INVISIBLE (-3150 2650);
FORCEPROP 1 LAST PATH I404
J 0
(-3477 2775);
DISPLAY 0.872340 (-3477 2775);
PAINT GREEN (-3477 2775);
DISPLAY INVISIBLE (-3477 2775);
FORCEADD TAP..1
(-3475 2875);
FORCEPROP 3 LASTPIN (-3525 2875) SIG_NAME M_E_CPU0_SB_DQS_DN<2>
J 0
(-3515 2885);
DISPLAY 0.659574 (-3515 2885);
PAINT MONO (-3515 2885);
DISPLAY INVISIBLE (-3515 2885);
FORCEPROP 1 LASTPIN (-3525 2875) BN 2
J 0
(-3537 2883);
DISPLAY 0.489362 (-3537 2883);
PAINT GREEN (-3537 2883);
FORCEPROP 2 LAST CDS_LIB mstr_standard
J 0
(-3475 2875);
DISPLAY 0.723404 (-3475 2875);
PAINT MONO (-3475 2875);
DISPLAY INVISIBLE (-3475 2875);
FORCEPROP 1 LAST BODY_TYPE PLUMBING
J 0
(-3475 2925);
DISPLAY 0.872340 (-3475 2925);
PAINT GREEN (-3475 2925);
DISPLAY INVISIBLE (-3475 2925);
FORCEPROP 1 LAST HDL_TAP TRUE
J 0
(-3150 2750);
DISPLAY 0.872340 (-3150 2750);
DISPLAY INVISIBLE (-3150 2750);
FORCEPROP 1 LAST PATH I405
J 0
(-3477 2875);
DISPLAY 0.872340 (-3477 2875);
PAINT GREEN (-3477 2875);
DISPLAY INVISIBLE (-3477 2875);
FORCEADD TAP..1
(-3675 2925);
FORCEPROP 3 LASTPIN (-3725 2925) SIG_NAME M_E_CPU0_SB_DQS_DP<2>
J 0
(-3715 2935);
DISPLAY 0.659574 (-3715 2935);
PAINT MONO (-3715 2935);
DISPLAY INVISIBLE (-3715 2935);
FORCEPROP 1 LASTPIN (-3725 2925) BN 2
J 0
(-3737 2933);
DISPLAY 0.489362 (-3737 2933);
PAINT GREEN (-3737 2933);
FORCEPROP 2 LAST CDS_LIB mstr_standard
J 0
(-3675 2925);
DISPLAY 0.723404 (-3675 2925);
PAINT MONO (-3675 2925);
DISPLAY INVISIBLE (-3675 2925);
FORCEPROP 1 LAST BODY_TYPE PLUMBING
J 0
(-3675 2975);
DISPLAY 0.872340 (-3675 2975);
PAINT GREEN (-3675 2975);
DISPLAY INVISIBLE (-3675 2975);
FORCEPROP 1 LAST HDL_TAP TRUE
J 0
(-3350 2800);
DISPLAY 0.872340 (-3350 2800);
DISPLAY INVISIBLE (-3350 2800);
FORCEPROP 1 LAST PATH I406
J 0
(-3677 2925);
DISPLAY 0.872340 (-3677 2925);
PAINT GREEN (-3677 2925);
DISPLAY INVISIBLE (-3677 2925);
FORCEADD TAP..1
(-3675 2825);
FORCEPROP 3 LASTPIN (-3725 2825) SIG_NAME M_E_CPU0_SB_DQS_DP<1>
J 0
(-3715 2835);
DISPLAY 0.659574 (-3715 2835);
PAINT MONO (-3715 2835);
DISPLAY INVISIBLE (-3715 2835);
FORCEPROP 1 LASTPIN (-3725 2825) BN 1
J 0
(-3737 2833);
DISPLAY 0.489362 (-3737 2833);
PAINT GREEN (-3737 2833);
FORCEPROP 2 LAST CDS_LIB mstr_standard
J 0
(-3675 2825);
DISPLAY 0.723404 (-3675 2825);
PAINT MONO (-3675 2825);
DISPLAY INVISIBLE (-3675 2825);
FORCEPROP 1 LAST BODY_TYPE PLUMBING
J 0
(-3675 2875);
DISPLAY 0.872340 (-3675 2875);
PAINT GREEN (-3675 2875);
DISPLAY INVISIBLE (-3675 2875);
FORCEPROP 1 LAST HDL_TAP TRUE
J 0
(-3350 2700);
DISPLAY 0.872340 (-3350 2700);
DISPLAY INVISIBLE (-3350 2700);
FORCEPROP 1 LAST PATH I407
J 0
(-3677 2825);
DISPLAY 0.872340 (-3677 2825);
PAINT GREEN (-3677 2825);
DISPLAY INVISIBLE (-3677 2825);
FORCEADD TAP..1
(-3475 2675);
FORCEPROP 3 LASTPIN (-3525 2675) SIG_NAME M_E_CPU0_SB_DQS_DN<0>
J 0
(-3515 2685);
DISPLAY 0.659574 (-3515 2685);
PAINT MONO (-3515 2685);
DISPLAY INVISIBLE (-3515 2685);
FORCEPROP 1 LASTPIN (-3525 2675) BN 0
J 0
(-3537 2683);
DISPLAY 0.489362 (-3537 2683);
PAINT GREEN (-3537 2683);
FORCEPROP 2 LAST CDS_LIB mstr_standard
J 0
(-3475 2675);
DISPLAY 0.723404 (-3475 2675);
PAINT MONO (-3475 2675);
DISPLAY INVISIBLE (-3475 2675);
FORCEPROP 1 LAST BODY_TYPE PLUMBING
J 0
(-3475 2725);
DISPLAY 0.872340 (-3475 2725);
PAINT GREEN (-3475 2725);
DISPLAY INVISIBLE (-3475 2725);
FORCEPROP 1 LAST HDL_TAP TRUE
J 0
(-3150 2550);
DISPLAY 0.872340 (-3150 2550);
DISPLAY INVISIBLE (-3150 2550);
FORCEPROP 1 LAST PATH I408
J 0
(-3477 2675);
DISPLAY 0.872340 (-3477 2675);
PAINT GREEN (-3477 2675);
DISPLAY INVISIBLE (-3477 2675);
FORCEADD TAP..1
(-3675 2725);
FORCEPROP 3 LASTPIN (-3725 2725) SIG_NAME M_E_CPU0_SB_DQS_DP<0>
J 0
(-3715 2735);
DISPLAY 0.659574 (-3715 2735);
PAINT MONO (-3715 2735);
DISPLAY INVISIBLE (-3715 2735);
FORCEPROP 1 LASTPIN (-3725 2725) BN 0
J 0
(-3737 2733);
DISPLAY 0.489362 (-3737 2733);
PAINT GREEN (-3737 2733);
FORCEPROP 2 LAST CDS_LIB mstr_standard
J 0
(-3675 2725);
DISPLAY 0.723404 (-3675 2725);
PAINT MONO (-3675 2725);
DISPLAY INVISIBLE (-3675 2725);
FORCEPROP 1 LAST BODY_TYPE PLUMBING
J 0
(-3675 2775);
DISPLAY 0.872340 (-3675 2775);
PAINT GREEN (-3675 2775);
DISPLAY INVISIBLE (-3675 2775);
FORCEPROP 1 LAST HDL_TAP TRUE
J 0
(-3350 2600);
DISPLAY 0.872340 (-3350 2600);
DISPLAY INVISIBLE (-3350 2600);
FORCEPROP 1 LAST PATH I409
J 0
(-3677 2725);
DISPLAY 0.872340 (-3677 2725);
PAINT GREEN (-3677 2725);
DISPLAY INVISIBLE (-3677 2725);
FORCEADD SCONN288_DDR506112002KQ..2
(-4625 3675);
FORCEPROP 1 LAST LOCATION J21
J 0
(-5225 5000);
DISPLAY 0.468085 (-5225 5000);
PAINT SKYBLUE (-5225 5000);
FORCEPROP 0 LAST $SEC 2
J 0
(-5075 5150);
DISPLAY 0.680851 (-5075 5150);
PAINT MONO (-5075 5150);
DISPLAY INVISIBLE (-5075 5150);
FORCEPROP 0 LAST CDS_SEC 2
J 0
(-5075 5150);
DISPLAY 1.021277 (-5075 5150);
DISPLAY INVISIBLE (-5075 5150);
FORCEPROP 0 LASTPIN (-3875 3725) $PN 12
J 0
(-3865 3735);
DISPLAY 0.680851 (-3865 3735);
PAINT MONO (-3865 3735);
FORCEPROP 0 LASTPIN (-3875 3775) $PN 11
J 0
(-3865 3785);
DISPLAY 0.680851 (-3865 3785);
PAINT MONO (-3865 3785);
FORCEPROP 0 LASTPIN (-3875 2675) $PN 105
J 0
(-3865 2685);
DISPLAY 0.680851 (-3865 2685);
PAINT MONO (-3865 2685);
FORCEPROP 0 LASTPIN (-3875 2725) $PN 104
J 0
(-3865 2735);
DISPLAY 0.680851 (-3865 2735);
PAINT MONO (-3865 2735);
FORCEPROP 0 LASTPIN (-3875 3825) $PN 23
J 0
(-3865 3835);
DISPLAY 0.680851 (-3865 3835);
PAINT MONO (-3865 3835);
FORCEPROP 0 LASTPIN (-3875 3875) $PN 22
J 0
(-3865 3885);
DISPLAY 0.680851 (-3865 3885);
PAINT MONO (-3865 3885);
FORCEPROP 0 LASTPIN (-3875 2775) $PN 116
J 0
(-3865 2785);
DISPLAY 0.680851 (-3865 2785);
PAINT MONO (-3865 2785);
FORCEPROP 0 LASTPIN (-3875 2825) $PN 115
J 0
(-3865 2835);
DISPLAY 0.680851 (-3865 2835);
PAINT MONO (-3865 2835);
FORCEPROP 0 LASTPIN (-3875 3925) $PN 34
J 0
(-3865 3935);
DISPLAY 0.680851 (-3865 3935);
PAINT MONO (-3865 3935);
FORCEPROP 0 LASTPIN (-3875 3975) $PN 33
J 0
(-3865 3985);
DISPLAY 0.680851 (-3865 3985);
PAINT MONO (-3865 3985);
FORCEPROP 0 LASTPIN (-3875 2875) $PN 127
J 0
(-3865 2885);
DISPLAY 0.680851 (-3865 2885);
PAINT MONO (-3865 2885);
FORCEPROP 0 LASTPIN (-3875 2925) $PN 126
J 0
(-3865 2935);
DISPLAY 0.680851 (-3865 2935);
PAINT MONO (-3865 2935);
FORCEPROP 0 LASTPIN (-3875 4025) $PN 45
J 0
(-3865 4035);
DISPLAY 0.680851 (-3865 4035);
PAINT MONO (-3865 4035);
FORCEPROP 0 LASTPIN (-3875 4075) $PN 44
J 0
(-3865 4085);
DISPLAY 0.680851 (-3865 4085);
PAINT MONO (-3865 4085);
FORCEPROP 0 LASTPIN (-3875 2975) $PN 138
J 0
(-3865 2985);
DISPLAY 0.680851 (-3865 2985);
PAINT MONO (-3865 2985);
FORCEPROP 0 LASTPIN (-3875 3025) $PN 137
J 0
(-3865 3035);
DISPLAY 0.680851 (-3865 3035);
PAINT MONO (-3865 3035);
FORCEPROP 0 LASTPIN (-3875 4125) $PN 56
J 0
(-3865 4135);
DISPLAY 0.680851 (-3865 4135);
PAINT MONO (-3865 4135);
FORCEPROP 0 LASTPIN (-3875 4175) $PN 55
J 0
(-3865 4185);
DISPLAY 0.680851 (-3865 4185);
PAINT MONO (-3865 4185);
FORCEPROP 0 LASTPIN (-3875 3075) $PN 238
J 0
(-3865 3085);
DISPLAY 0.680851 (-3865 3085);
PAINT MONO (-3865 3085);
FORCEPROP 0 LASTPIN (-3875 3125) $PN 239
J 0
(-3865 3135);
DISPLAY 0.680851 (-3865 3135);
PAINT MONO (-3865 3135);
FORCEPROP 0 LASTPIN (-3875 4225) $PN 156
J 0
(-3865 4235);
DISPLAY 0.680851 (-3865 4235);
PAINT MONO (-3865 4235);
FORCEPROP 0 LASTPIN (-3875 4275) $PN 157
J 0
(-3865 4285);
DISPLAY 0.680851 (-3865 4285);
PAINT MONO (-3865 4285);
FORCEPROP 0 LASTPIN (-3875 3175) $PN 249
J 0
(-3865 3185);
DISPLAY 0.680851 (-3865 3185);
PAINT MONO (-3865 3185);
FORCEPROP 0 LASTPIN (-3875 3225) $PN 250
J 0
(-3865 3235);
DISPLAY 0.680851 (-3865 3235);
PAINT MONO (-3865 3235);
FORCEPROP 0 LASTPIN (-3875 4325) $PN 167
J 0
(-3865 4335);
DISPLAY 0.680851 (-3865 4335);
PAINT MONO (-3865 4335);
FORCEPROP 0 LASTPIN (-3875 4375) $PN 168
J 0
(-3865 4385);
DISPLAY 0.680851 (-3865 4385);
PAINT MONO (-3865 4385);
FORCEPROP 0 LASTPIN (-3875 3275) $PN 260
J 0
(-3865 3285);
DISPLAY 0.680851 (-3865 3285);
PAINT MONO (-3865 3285);
FORCEPROP 0 LASTPIN (-3875 3325) $PN 261
J 0
(-3865 3335);
DISPLAY 0.680851 (-3865 3335);
PAINT MONO (-3865 3335);
FORCEPROP 0 LASTPIN (-3875 4425) $PN 178
J 0
(-3865 4435);
DISPLAY 0.680851 (-3865 4435);
PAINT MONO (-3865 4435);
FORCEPROP 0 LASTPIN (-3875 4475) $PN 179
J 0
(-3865 4485);
DISPLAY 0.680851 (-3865 4485);
PAINT MONO (-3865 4485);
FORCEPROP 0 LASTPIN (-3875 3375) $PN 271
J 0
(-3865 3385);
DISPLAY 0.680851 (-3865 3385);
PAINT MONO (-3865 3385);
FORCEPROP 0 LASTPIN (-3875 3425) $PN 272
J 0
(-3865 3435);
DISPLAY 0.680851 (-3865 3435);
PAINT MONO (-3865 3435);
FORCEPROP 0 LASTPIN (-3875 4525) $PN 189
J 0
(-3865 4535);
DISPLAY 0.680851 (-3865 4535);
PAINT MONO (-3865 4535);
FORCEPROP 0 LASTPIN (-3875 4575) $PN 190
J 0
(-3865 4585);
DISPLAY 0.680851 (-3865 4585);
PAINT MONO (-3865 4585);
FORCEPROP 0 LASTPIN (-3875 3475) $PN 282
J 0
(-3865 3485);
DISPLAY 0.680851 (-3865 3485);
PAINT MONO (-3865 3485);
FORCEPROP 0 LASTPIN (-3875 3525) $PN 283
J 0
(-3865 3535);
DISPLAY 0.680851 (-3865 3535);
PAINT MONO (-3865 3535);
FORCEPROP 0 LASTPIN (-3875 4625) $PN 200
J 0
(-3865 4635);
DISPLAY 0.680851 (-3865 4635);
PAINT MONO (-3865 4635);
FORCEPROP 0 LASTPIN (-3875 4675) $PN 201
J 0
(-3865 4685);
DISPLAY 0.680851 (-3865 4685);
PAINT MONO (-3865 4685);
FORCEPROP 0 LASTPIN (-3875 3575) $PN 94
J 0
(-3865 3585);
DISPLAY 0.680851 (-3865 3585);
PAINT MONO (-3865 3585);
FORCEPROP 0 LASTPIN (-3875 3625) $PN 93
J 0
(-3865 3635);
DISPLAY 0.680851 (-3865 3635);
PAINT MONO (-3865 3635);
FORCEPROP 2 LAST PART_TYPE SMLF
J 0
(-5075 5100);
DISPLAY 1.021277 (-5075 5100);
FORCEPROP 2 LAST VALUE SCONN288_DDR506112002KQ
J 0
(-5075 5050);
DISPLAY 0.489362 (-5075 5050);
PAINT SKYBLUE (-5075 5050);
FORCEPROP 1 LAST MATERIAL IO
J 0
(-5225 4850);
DISPLAY 0.468085 (-5225 4850);
PAINT SKYBLUE (-5225 4850);
FORCEPROP 1 LAST PART_NUMBER DFHST8FS479
J 0
(-5225 4925);
DISPLAY 0.468085 (-5225 4925);
PAINT SKYBLUE (-5225 4925);
FORCEPROP 1 LAST CDS_LMAN_SYM_OUTLINE -600,1150,600,-1150
J 0
(-4625 3675);
DISPLAY 0.468085 (-4625 3675);
PAINT GREEN (-4625 3675);
DISPLAY INVISIBLE (-4625 3675);
FORCEPROP 1 LAST PATH I410
J 0
(-4625 3675);
DISPLAY 0.723404 (-4625 3675);
PAINT GREEN (-4625 3675);
DISPLAY INVISIBLE (-4625 3675);
FORCEPROP 1 LAST NEEDS_NO_SIZE TRUE
J 0
(-4625 3675);
DISPLAY 0.723404 (-4625 3675);
PAINT GREEN (-4625 3675);
DISPLAY INVISIBLE (-4625 3675);
FORCEPROP 2 LAST CDS_LIB pure_quanta
J 0
(-4625 3675);
DISPLAY INVISIBLE (-4625 3675);
FORCEADD GND..1
(-2975 5700);
FORCEPROP 3 LASTPIN (-2975 5750) SIG_NAME GND\g
J 0
(-2965 5760);
DISPLAY 0.659574 (-2965 5760);
PAINT MONO (-2965 5760);
DISPLAY INVISIBLE (-2965 5760);
FORCEPROP 2 LAST CDS_LIB pure_quanta_power
J 0
(-2975 5700);
DISPLAY INVISIBLE (-2975 5700);
FORCEPROP 2 LAST BOM_COST MEM
J 0
(-2950 5825);
DISPLAY 0.659574 (-2950 5825);
DISPLAY INVISIBLE (-2950 5825);
FORCEPROP 1 LAST SIZE 1B
J 0
(-2900 5650);
DISPLAY 0.723404 (-2900 5650);
PAINT GREEN (-2900 5650);
DISPLAY INVISIBLE (-2900 5650);
FORCEPROP 1 LAST PATH I411
J 0
(-2900 5700);
DISPLAY 0.872340 (-2900 5700);
PAINT AQUA (-2900 5700);
DISPLAY INVISIBLE (-2900 5700);
FORCEPROP 2 LAST ROOM MEM_EFGH_DECOUPLING_CAPS
J 0
(-2950 5775);
DISPLAY 0.659574 (-2950 5775);
PAINT RED (-2950 5775);
DISPLAY INVISIBLE (-2950 5775);
FORCEPROP 1 LAST HDL_POWER GND
J 0
(-2975 5850);
DISPLAY 0.723404 (-2975 5850);
PAINT GREEN (-2975 5850);
DISPLAY INVISIBLE (-2975 5850);
FORCEADD Q_CAP..1
R 2
(-2975 6050);
FORCEPROP 1 LAST LOCATION C151
J 2
(-3025 6150);
DISPLAY 0.489362 (-3025 6150);
PAINT SKYBLUE (-3025 6150);
FORCEPROP 0 LAST $SEC 1
J 0
(-3025 6200);
DISPLAY 0.680851 (-3025 6200);
PAINT MONO (-3025 6200);
DISPLAY INVISIBLE (-3025 6200);
FORCEPROP 0 LAST CDS_SEC 1
J 0
(-3025 6200);
DISPLAY 0.680851 (-3025 6200);
DISPLAY INVISIBLE (-3025 6200);
FORCEPROP 1 LASTPIN (-2975 6150) $PN 1
J 2
(-2985 6130);
DISPLAY 0.489362 (-2985 6130);
PAINT MONO (-2985 6130);
FORCEPROP 1 LASTPIN (-2975 5950) $PN 2
J 2
(-2985 5930);
DISPLAY 0.489362 (-2985 5930);
PAINT MONO (-2985 5930);
FORCEPROP 1 LAST MATERIAL X6S
J 2
(-3025 5950);
DISPLAY 0.489362 (-3025 5950);
PAINT SKYBLUE (-3025 5950);
FORCEPROP 1 LAST TOLERANCE 10%
J 2
(-3025 6000);
DISPLAY 0.489362 (-3025 6000);
PAINT SKYBLUE (-3025 6000);
FORCEPROP 1 LAST VALUE 10UF
J 2
(-3025 6100);
DISPLAY 0.489362 (-3025 6100);
PAINT SKYBLUE (-3025 6100);
FORCEPROP 1 LAST PART_NUMBER CH6104KEA00
J 2
(-3025 5900);
DISPLAY 0.489362 (-3025 5900);
PAINT SKYBLUE (-3025 5900);
FORCEPROP 1 LAST VOLTAGE 25V
J 2
(-3025 6050);
DISPLAY 0.489362 (-3025 6050);
PAINT SKYBLUE (-3025 6050);
FORCEPROP 1 LAST PACK_TYPE C0805
J 2
(-3025 5850);
DISPLAY 0.489362 (-3025 5850);
PAINT SKYBLUE (-3025 5850);
FORCEPROP 0 LAST BOM_COST MEM
J 2
(-3030 6195);
DISPLAY 0.595745 (-3030 6195);
PAINT MONO (-3030 6195);
DISPLAY INVISIBLE (-3030 6195);
FORCEPROP 2 LAST CDS_LIB pure_quanta
J 0
(-2975 6050);
DISPLAY INVISIBLE (-2975 6050);
FORCEPROP 1 LAST PATH I412
J 2
(-3025 6200);
DISPLAY 0.978723 (-3025 6200);
PAINT WHITE (-3025 6200);
DISPLAY INVISIBLE (-3025 6200);
FORCEPROP 0 LAST ROOM MEM_CH_A_CPU0_DIMM1
J 2
(-3030 6195);
DISPLAY 0.595745 (-3030 6195);
PAINT RED (-3030 6195);
DISPLAY INVISIBLE (-3030 6195);
FORCEADD Q_CAP..1
R 2
(-2400 6050);
FORCEPROP 1 LAST LOCATION C153
J 2
(-2450 6150);
DISPLAY 0.489362 (-2450 6150);
PAINT SKYBLUE (-2450 6150);
FORCEPROP 0 LAST $SEC 1
J 0
(-2450 6200);
DISPLAY 0.680851 (-2450 6200);
PAINT MONO (-2450 6200);
DISPLAY INVISIBLE (-2450 6200);
FORCEPROP 0 LAST CDS_SEC 1
J 0
(-2450 6200);
DISPLAY 0.680851 (-2450 6200);
DISPLAY INVISIBLE (-2450 6200);
FORCEPROP 1 LASTPIN (-2400 6150) $PN 1
J 2
(-2410 6130);
DISPLAY 0.489362 (-2410 6130);
PAINT MONO (-2410 6130);
FORCEPROP 1 LASTPIN (-2400 5950) $PN 2
J 2
(-2410 5930);
DISPLAY 0.489362 (-2410 5930);
PAINT MONO (-2410 5930);
FORCEPROP 1 LAST MATERIAL X6S
J 2
(-2450 5950);
DISPLAY 0.489362 (-2450 5950);
PAINT SKYBLUE (-2450 5950);
FORCEPROP 1 LAST TOLERANCE 10%
J 2
(-2450 6000);
DISPLAY 0.489362 (-2450 6000);
PAINT SKYBLUE (-2450 6000);
FORCEPROP 1 LAST VALUE 10UF
J 2
(-2450 6100);
DISPLAY 0.489362 (-2450 6100);
PAINT SKYBLUE (-2450 6100);
FORCEPROP 1 LAST PART_NUMBER CH6104KEA00
J 2
(-2450 5900);
DISPLAY 0.489362 (-2450 5900);
PAINT SKYBLUE (-2450 5900);
FORCEPROP 1 LAST VOLTAGE 25V
J 2
(-2450 6050);
DISPLAY 0.489362 (-2450 6050);
PAINT SKYBLUE (-2450 6050);
FORCEPROP 1 LAST PACK_TYPE C0805
J 2
(-2450 5850);
DISPLAY 0.489362 (-2450 5850);
PAINT SKYBLUE (-2450 5850);
FORCEPROP 0 LAST BOM_COST MEM
J 2
(-2455 6195);
DISPLAY 0.595745 (-2455 6195);
PAINT MONO (-2455 6195);
DISPLAY INVISIBLE (-2455 6195);
FORCEPROP 2 LAST CDS_LIB pure_quanta
J 0
(-2400 6050);
DISPLAY INVISIBLE (-2400 6050);
FORCEPROP 1 LAST PATH I413
J 2
(-2450 6200);
DISPLAY 0.978723 (-2450 6200);
PAINT WHITE (-2450 6200);
DISPLAY INVISIBLE (-2450 6200);
FORCEPROP 0 LAST ROOM MEM_CH_A_CPU0_DIMM1
J 2
(-2455 6195);
DISPLAY 0.595745 (-2455 6195);
PAINT RED (-2455 6195);
DISPLAY INVISIBLE (-2455 6195);
FORCEADD UNIVERSAL_POWER..1
(-2975 6375);
FORCEPROP 3 LASTPIN (-2975 6325) SIG_NAME P12V_MEM_1\g
J 0
(-2965 6335);
DISPLAY 0.659574 (-2965 6335);
PAINT MONO (-2965 6335);
DISPLAY INVISIBLE (-2965 6335);
FORCEPROP 1 LAST HDL_POWER P12V_MEM_1
J 1
(-3000 6425);
DISPLAY 0.489362 (-3000 6425);
PAINT GREEN (-3000 6425);
FORCEPROP 2 LAST BOM_COST VR_SYSTEM
J 0
(-2975 6475);
DISPLAY 0.617021 (-2975 6475);
PAINT PURPLE (-2975 6475);
DISPLAY INVISIBLE (-2975 6475);
FORCEPROP 2 LAST CDS_LIB pure_quanta_power
J 0
(-2975 6375);
DISPLAY INVISIBLE (-2975 6375);
FORCEPROP 1 LAST PATH I414
J 0
(-2925 6400);
DISPLAY 0.872340 (-2925 6400);
PAINT AQUA (-2925 6400);
DISPLAY INVISIBLE (-2925 6400);
FORCEADD OFFPAGE..1
(-8575 2875);
FORCEPROP 2 LAST $XR5 90 
J 0
(-9307 2875);
DISPLAY 0.638298 (-9307 2875);
PAINT MONO (-9307 2875);
FORCEPROP 2 LAST $XR4 88 
J 0
(-9217 2875);
DISPLAY 0.638298 (-9217 2875);
PAINT MONO (-9217 2875);
FORCEPROP 2 LAST $XR3 87 
J 0
(-9127 2875);
DISPLAY 0.638298 (-9127 2875);
PAINT MONO (-9127 2875);
FORCEPROP 2 LAST $XR2 86 
J 0
(-9037 2875);
DISPLAY 0.638298 (-9037 2875);
PAINT MONO (-9037 2875);
FORCEPROP 2 LAST $XR1 85 
J 0
(-8947 2875);
DISPLAY 0.638298 (-8947 2875);
PAINT MONO (-8947 2875);
FORCEPROP 2 LAST $XR0 136 
J 0
(-8857 2875);
DISPLAY 0.638298 (-8857 2875);
PAINT MONO (-8857 2875);
FORCEPROP 2 LAST PATH I415
J 0
(-8850 2925);
DISPLAY 0.680851 (-8850 2925);
DISPLAY INVISIBLE (-8850 2925);
FORCEPROP 1 LAST COMMENT_BODY TRUE
J 0
(-8450 2775);
DISPLAY 0.872340 (-8450 2775);
PAINT GREEN (-8450 2775);
DISPLAY INVISIBLE (-8450 2775);
FORCEPROP 1 LAST OFFPAGE TRUE
J 0
(-8250 2750);
DISPLAY 0.872340 (-8250 2750);
PAINT GREEN (-8250 2750);
DISPLAY INVISIBLE (-8250 2750);
FORCEPROP 2 LAST CDS_LIB mstr_standard
J 0
(-8575 2875);
DISPLAY 0.808511 (-8575 2875);
DISPLAY INVISIBLE (-8575 2875);
FORCEADD Q_RES..1
(-8025 2875);
FORCEPROP 1 LAST $LOCATION R1572
J 0
(-8075 2900);
DISPLAY 0.510638 (-8075 2900);
PAINT SKYBLUE (-8075 2900);
FORCEPROP 0 LAST CDS_LOCATION R1572
J 0
(-8075 2975);
DISPLAY 0.680851 (-8075 2975);
DISPLAY INVISIBLE (-8075 2975);
FORCEPROP 0 LAST $SEC 1
J 0
(-8075 2975);
DISPLAY 0.680851 (-8075 2975);
PAINT MONO (-8075 2975);
DISPLAY INVISIBLE (-8075 2975);
FORCEPROP 0 LAST CDS_SEC 1
J 0
(-8075 2975);
DISPLAY 0.680851 (-8075 2975);
DISPLAY INVISIBLE (-8075 2975);
FORCEPROP 1 LASTPIN (-8125 2875) $PN 1
J 0
(-8113 2887);
DISPLAY 0.787234 (-8113 2887);
PAINT MONO (-8113 2887);
FORCEPROP 1 LASTPIN (-7925 2875) $PN 2
J 0
(-7963 2887);
DISPLAY 0.787234 (-7963 2887);
PAINT MONO (-7963 2887);
FORCEPROP 1 LAST VALUE 49.9
J 2
(-7900 2925);
DISPLAY 0.510638 (-7900 2925);
PAINT SKYBLUE (-7900 2925);
FORCEPROP 1 LAST PART_NUMBER CS04992FB07
J 0
(-8075 2975);
DISPLAY 0.978723 (-8075 2975);
DISPLAY INVISIBLE (-8075 2975);
FORCEPROP 1 LAST TOLERANCE 1%
J 0
(-8025 2775);
DISPLAY 0.978723 (-8025 2775);
DISPLAY INVISIBLE (-8025 2775);
FORCEPROP 1 LAST WATTAGE 1/16W
J 2
(-8050 2725);
DISPLAY 0.978723 (-8050 2725);
DISPLAY INVISIBLE (-8050 2725);
FORCEPROP 1 LAST PACK_TYPE 0402LF
J 0
(-7775 2725);
DISPLAY 0.978723 (-7775 2725);
DISPLAY INVISIBLE (-7775 2725);
FORCEPROP 1 LAST MATERIAL CHIP
J 0
(-8025 2725);
DISPLAY 0.978723 (-8025 2725);
DISPLAY INVISIBLE (-8025 2725);
FORCEPROP 1 LAST PATH I416
J 0
(-8075 3025);
DISPLAY 0.978723 (-8075 3025);
PAINT WHITE (-8075 3025);
DISPLAY INVISIBLE (-8075 3025);
FORCEPROP 2 LAST CDS_LIB pure_quanta
J 0
(-8025 2875);
DISPLAY INVISIBLE (-8025 2875);
FORCEADD DNS..2
(-8575 2475);
PAINT RED (-8575 2475);
FORCEPROP 2 LAST CDS_LIB mstr_misc
J 0
(-8575 2475);
DISPLAY INVISIBLE (-8575 2475);
FORCEPROP 1 LAST COMMENT_BODY TRUE
R 1
J 0
(-8500 2250);
DISPLAY 0.872340 (-8500 2250);
PAINT PEACH (-8500 2250);
DISPLAY INVISIBLE (-8500 2250);
FORCEADD QUANTA_TITLE_BLOCK_C..1
(-100 100);
FORCEPROP 0 LAST CDS_CON_LAST_MODIFIED Fri Mar 11 14:52:55 2022
J 0
(-1985 115);
DISPLAY INVISIBLE (-1985 115);
FORCEPROP 1 LAST CUSTOM_TXT_CDS <CON_LAST_MODIFIED>
J 0
(-1985 115);
DISPLAY 0.978723 (-1985 115);
FORCEPROP 2 LAST CUSTOM_TXT_CDS <XR_PAGE_TITLE>
J 0
(-7990 5350);
DISPLAY 0.638298 (-7990 5350);
PAINT PINK (-7990 5350);
DISPLAY INVISIBLE (-7990 5350);
FORCEPROP 1 LAST CUSTOM_TXT_CDS <NAME_2>
J 0
(-3275 150);
FORCEPROP 1 LAST CUSTOM_TXT_CDS <NAME_1>
J 0
(-3275 275);
FORCEPROP 1 LAST CUSTOM_TXT_CDS <Q_NUMBER>
J 0
(-1503 203);
DISPLAY 1.212766 (-1503 203);
FORCEPROP 1 LAST CUSTOM_TXT_CDS <Q_PROJ>
J 0
(-2482 202);
DISPLAY 1.212766 (-2482 202);
FORCEPROP 1 LAST CUSTOM_TXT_CDS <Q_REV>
J 0
(-284 203);
DISPLAY 1.212766 (-284 203);
FORCEPROP 1 LAST CUSTOM_TXT_CDS <CON_PAGE_NUM> OF <CON_TOTAL_PAGES>
J 0
(-546 118);
DISPLAY 0.978723 (-546 118);
FORCEPROP 1 LAST Q_TITLE DDR5 - CPU0 CHE
J 0
(-9425 150);
DISPLAY 2.446809 (-9425 150);
PAINT GREEN (-9425 150);
FORCEPROP 1 LAST Q_DEPT BU9
J 1
(-3863 149);
DISPLAY 1.957447 (-3863 149);
PAINT GREEN (-3863 149);
FORCEPROP 2 LAST PAGE_BORDER TRUE
J 0
(-7990 5350);
DISPLAY 0.638298 (-7990 5350);
PAINT PINK (-7990 5350);
DISPLAY INVISIBLE (-7990 5350);
FORCEPROP 1 LAST CDS_LMAN_SYM_OUTLINE -9475,6775,100,-125
J 0
(-100 100);
DISPLAY 0.468085 (-100 100);
PAINT GREEN (-100 100);
DISPLAY INVISIBLE (-100 100);
FORCEPROP 2 LAST CDS_LIB pure_quanta
J 0
(-100 100);
DISPLAY INVISIBLE (-100 100);
FORCEPROP 1 LAST COMMENT_BODY TRUE
J 0
(-88 87);
DISPLAY 0.978723 (-88 87);
PAINT GREEN (-88 87);
DISPLAY INVISIBLE (-88 87);
FORCEPROP 2 LAST CDS_XR_PAGE_TITLE CR-89 : @T6G_MB_LIB.T6G(SCH_1):PAGE89
J 0
(-7990 5350);
DISPLAY 0.638298 (-7990 5350);
PAINT PINK (-7990 5350);
DISPLAY INVISIBLE (-7990 5350);
WIRE 17 -1 (-6225 5600)(-6225 5550);
WIRE 17 -1 (-6225 5650)(-6225 5600);
WIRE 17 -1 (-6225 5550)(-6225 5500);
WIRE 17 -1 (-6225 5500)(-6225 5450);
WIRE 17 -1 (-6225 5650)(-5675 5650);
FORCEPROP 2 LAST SIG_NAME M_E_CPU0_SA_DQ<31:0>
J 0
(-6160 5660);
DISPLAY 0.489362 (-6160 5660);
WIRE 17 -1 (-8025 4200)(-8025 4150);
WIRE 17 -1 (-8025 4200)(-8025 4225);
WIRE 17 -1 (-8025 4100)(-8025 4150);
WIRE 17 -1 (-8025 4100)(-8025 4050);
WIRE 17 -1 (-8025 4225)(-8525 4225);
FORCEPROP 2 LAST SIG_NAME M_E_CPU0_SA_CB<7:0>
J 0
(-8475 4235);
DISPLAY 0.489362 (-8475 4235);
WIRE 17 -1 (-8025 4000)(-8025 4050);
WIRE 17 -1 (-8025 3950)(-8025 4000);
WIRE 17 -1 (-8025 3900)(-8025 3950);
WIRE 17 -1 (-8025 3850)(-8025 3900);
WIRE 17 -1 (-8025 3750)(-8025 3700);
WIRE 17 -1 (-8025 3750)(-8025 3775);
WIRE 17 -1 (-8025 3650)(-8025 3700);
WIRE 17 -1 (-8025 3650)(-8025 3600);
WIRE 17 -1 (-8025 3775)(-8525 3775);
FORCEPROP 2 LAST SIG_NAME M_E_CPU0_SB_CB<7:0>
J 0
(-8475 3785);
DISPLAY 0.489362 (-8475 3785);
WIRE 17 -1 (-8025 5300)(-8025 5350);
WIRE 17 -1 (-8025 5350)(-8025 5400);
WIRE 17 -1 (-8025 5400)(-8025 5450);
WIRE 17 -1 (-8025 5450)(-8025 5500);
WIRE 17 -1 (-8025 5500)(-8025 5550);
WIRE 17 -1 (-8025 5550)(-8025 5600);
WIRE 17 -1 (-8025 5600)(-8025 5625);
WIRE 17 -1 (-8025 5625)(-8525 5625);
FORCEPROP 2 LAST SIG_NAME M_E_CPU0_SA_CA<6:0>
J 0
(-8510 5635);
DISPLAY 0.489362 (-8510 5635);
WIRE 17 -1 (-8025 4900)(-8025 4950);
WIRE 17 -1 (-8025 4950)(-8025 5000);
WIRE 17 -1 (-8025 5000)(-8025 5050);
WIRE 17 -1 (-8025 5050)(-8025 5100);
WIRE 17 -1 (-8025 5100)(-8025 5150);
WIRE 17 -1 (-8025 5150)(-8025 5200);
WIRE 17 -1 (-8025 5200)(-8025 5225);
WIRE 17 -1 (-8025 5225)(-8525 5225);
FORCEPROP 2 LAST SIG_NAME M_E_CPU0_SB_CA<6:0>
J 0
(-8510 5235);
DISPLAY 0.489362 (-8510 5235);
WIRE 17 -1 (-8025 3550)(-8025 3600);
WIRE 17 -1 (-8025 3500)(-8025 3550);
WIRE 17 -1 (-8025 3450)(-8025 3500);
WIRE 17 -1 (-8025 3400)(-8025 3450);
WIRE 17 -1 (-6225 5450)(-6225 5400);
WIRE 17 -1 (-6225 5400)(-6225 5350);
WIRE 17 -1 (-6225 5350)(-6225 5300);
WIRE 17 -1 (-6225 5300)(-6225 5250);
WIRE 17 -1 (-6225 5250)(-6225 5200);
WIRE 17 -1 (-6225 5200)(-6225 5150);
WIRE 17 -1 (-6225 5150)(-6225 5100);
WIRE 17 -1 (-6225 5100)(-6225 5050);
WIRE 17 -1 (-6225 5050)(-6225 5000);
WIRE 17 -1 (-6225 5000)(-6225 4950);
WIRE 17 -1 (-6225 4950)(-6225 4900);
WIRE 17 -1 (-6225 4900)(-6225 4850);
WIRE 17 -1 (-6225 4800)(-6225 4850);
WIRE 17 -1 (-6225 4750)(-6225 4800);
WIRE 17 -1 (-6225 4700)(-6225 4750);
WIRE 17 -1 (-6225 4650)(-6225 4700);
WIRE 17 -1 (-6225 4650)(-6225 4600);
WIRE 17 -1 (-6225 4600)(-6225 4550);
WIRE 17 -1 (-6225 4550)(-6225 4500);
WIRE 17 -1 (-6225 4500)(-6225 4450);
WIRE 17 -1 (-6225 4450)(-6225 4400);
WIRE 17 -1 (-6225 4400)(-6225 4350);
WIRE 17 -1 (-6225 4350)(-6225 4300);
WIRE 17 -1 (-6225 4300)(-6225 4250);
WIRE 17 -1 (-6225 4200)(-6225 4250);
WIRE 17 -1 (-6225 4150)(-6225 4200);
WIRE 17 -1 (-6225 4100)(-6225 4150);
WIRE 17 -1 (-6225 4050)(-6225 4100);
WIRE 17 -1 (-6225 3950)(-6225 3900);
WIRE 17 -1 (-6225 4000)(-6225 3950);
WIRE 17 -1 (-6225 3900)(-6225 3850);
WIRE 17 -1 (-6225 3850)(-6225 3800);
WIRE 17 -1 (-6225 4000)(-5675 4000);
FORCEPROP 2 LAST SIG_NAME M_E_CPU0_SB_DQ<31:0>
J 0
(-6160 4010);
DISPLAY 0.489362 (-6160 4010);
WIRE 17 -1 (-6225 3800)(-6225 3750);
WIRE 17 -1 (-6225 3750)(-6225 3700);
WIRE 17 -1 (-6225 3700)(-6225 3650);
WIRE 17 -1 (-6225 3650)(-6225 3600);
WIRE 17 -1 (-6225 3600)(-6225 3550);
WIRE 17 -1 (-6225 3550)(-6225 3500);
WIRE 17 -1 (-6225 3500)(-6225 3450);
WIRE 17 -1 (-6225 3450)(-6225 3400);
WIRE 17 -1 (-6225 3400)(-6225 3350);
WIRE 17 -1 (-6225 3350)(-6225 3300);
WIRE 17 -1 (-6225 3300)(-6225 3250);
WIRE 17 -1 (-6225 3250)(-6225 3200);
WIRE 17 -1 (-6225 3150)(-6225 3200);
WIRE 17 -1 (-6225 3100)(-6225 3150);
WIRE 17 -1 (-6225 3050)(-6225 3100);
WIRE 17 -1 (-6225 3000)(-6225 3050);
WIRE 17 -1 (-6225 3000)(-6225 2950);
WIRE 17 -1 (-6225 2950)(-6225 2900);
WIRE 17 -1 (-6225 2900)(-6225 2850);
WIRE 17 -1 (-6225 2850)(-6225 2800);
WIRE 17 -1 (-6225 2800)(-6225 2750);
WIRE 17 -1 (-6225 2750)(-6225 2700);
WIRE 17 -1 (-6225 2700)(-6225 2650);
WIRE 17 -1 (-6225 2650)(-6225 2600);
WIRE 17 -1 (-6225 2550)(-6225 2600);
WIRE 17 -1 (-6225 2500)(-6225 2550);
WIRE 17 -1 (-6225 2450)(-6225 2500);
WIRE 17 -1 (-6225 2400)(-6225 2450);
WIRE 17 -1 (-3425 4450)(-3425 4350);
WIRE 17 -1 (-3425 4550)(-3425 4450);
WIRE 17 -1 (-3425 4350)(-3425 4250);
WIRE 17 -1 (-3425 4150)(-3425 4250);
WIRE 17 -1 (-3425 4650)(-3425 4550);
WIRE 17 -1 (-3425 4675)(-3425 4650);
WIRE 17 -1 (-3425 4050)(-3425 4150);
WIRE 17 -1 (-3425 3950)(-3425 4050);
WIRE 17 -1 (-3425 4675)(-2725 4675);
FORCEPROP 2 LAST SIG_NAME M_E_CPU0_SA_DQS_DN<9:0>
J 0
(-3360 4685);
DISPLAY 0.489362 (-3360 4685);
WIRE 17 -1 (-3625 4400)(-3625 4300);
WIRE 17 -1 (-3625 4500)(-3625 4400);
WIRE 17 -1 (-3625 4200)(-3625 4300);
WIRE 17 -1 (-3625 4100)(-3625 4200);
WIRE 17 -1 (-3625 4600)(-3625 4500);
WIRE 17 -1 (-3625 4700)(-3625 4600);
WIRE 17 -1 (-3625 4000)(-3625 4100);
WIRE 17 -1 (-3625 4000)(-3625 3900);
WIRE 17 -1 (-3625 4725)(-3625 4700);
WIRE 17 -1 (-3625 4725)(-2725 4725);
FORCEPROP 2 LAST SIG_NAME M_E_CPU0_SA_DQS_DP<9:0>
J 0
(-3360 4735);
DISPLAY 0.489362 (-3360 4735);
WIRE 17 -1 (-3625 3550)(-3625 3450);
WIRE 17 -1 (-3625 3650)(-3625 3550);
WIRE 17 -1 (-3625 3450)(-3625 3350);
WIRE 17 -1 (-3625 3350)(-3625 3250);
WIRE 17 -1 (-3625 3675)(-3625 3650);
WIRE 17 -1 (-3625 3675)(-2725 3675);
FORCEPROP 2 LAST SIG_NAME M_E_CPU0_SB_DQS_DP<9:0>
J 0
(-3360 3685);
DISPLAY 0.489362 (-3360 3685);
WIRE 17 -1 (-3425 3500)(-3425 3400);
WIRE 17 -1 (-3425 3600)(-3425 3500);
WIRE 17 -1 (-3425 3400)(-3425 3300);
WIRE 17 -1 (-3425 3300)(-3425 3200);
WIRE 17 -1 (-3425 3625)(-3425 3600);
WIRE 17 -1 (-3425 3625)(-2725 3625);
FORCEPROP 2 LAST SIG_NAME M_E_CPU0_SB_DQS_DN<9:0>
J 0
(-3360 3635);
DISPLAY 0.489362 (-3360 3635);
WIRE 17 -1 (-3625 3150)(-3625 3250);
WIRE 17 -1 (-3625 3050)(-3625 3150);
WIRE 17 -1 (-3625 2950)(-3625 3050);
WIRE 17 -1 (-3425 3850)(-3425 3750);
WIRE 17 -1 (-3425 3950)(-3425 3850);
WIRE 17 -1 (-3625 3900)(-3625 3800);
WIRE 17 -1 (-3425 2800)(-3425 2700);
WIRE 17 -1 (-3425 2900)(-3425 2800);
WIRE 17 -1 (-3425 2900)(-3425 3000);
WIRE 17 -1 (-3425 3000)(-3425 3100);
WIRE 17 -1 (-3425 3100)(-3425 3200);
WIRE 17 -1 (-3625 2850)(-3625 2750);
WIRE 17 -1 (-3625 2950)(-3625 2850);
WIRE 16 -1 (-6650 1250)(-6650 1325);
WIRE 16 -1 (-8875 3225)(-8875 3300);
WIRE 16 -1 (-8600 2575)(-8600 2600);
WIRE 16 -1 (-8875 3500)(-8875 3525);
WIRE 16 -1 (-8875 3525)(-8775 3525);
WIRE 16 -1 (-8775 3525)(-8775 3600);
WIRE 16 -1 (-8775 3125)(-8775 3525);
WIRE 16 -1 (-8775 3125)(-7725 3125);
WIRE 16 -1 (-7725 3025)(-8525 3025);
FORCEPROP 2 LAST SIG_NAME I3C_SPD_DDRAF_CPU0_SDA
J 0
(-8535 3035);
DISPLAY 0.489362 (-8535 3035);
WIRE 16 -1 (-8125 2875)(-8525 2875);
FORCEPROP 2 LAST SIG_NAME I3C_SPD_DDRAF_CPU0_SCL
J 0
(-8585 2885);
DISPLAY 0.489362 (-8585 2885);
WIRE 16 -1 (-7725 2975)(-7825 2975);
FORCEPROP 2 LAST SIG_NAME I3C_SPD_DDRE_CPU0_SCL
J 0
(-8210 2985);
DISPLAY 0.446809 (-8210 2985);
FORCEPROP 2 LASTPROP $XRERR UNIQUE?
J 0
(-8450 2985);
DISPLAY 0.638298 (-8450 2985);
PAINT MONO (-8450 2985);
DISPLAY INVISIBLE (-8450 2985);
WIRE 16 -1 (-7825 2975)(-7825 2875);
WIRE 16 -1 (-7825 2875)(-7925 2875);
WIRE 16 -1 (-7725 2725)(-8400 2725);
FORCEPROP 2 LAST SIG_NAME PWRGD_CHE_CPU0_DIMM
J 0
(-8285 2735);
DISPLAY 0.489362 (-8285 2735);
FORCEPROP 2 LASTPROP $XRERR UNIQUE?
J 0
(-8525 2735);
DISPLAY 0.638298 (-8525 2735);
PAINT MONO (-8525 2735);
DISPLAY INVISIBLE (-8525 2735);
WIRE 16 -1 (-8400 2325)(-8400 2725);
WIRE 16 -1 (-8400 2325)(-8600 2325);
WIRE 16 -1 (-8600 2325)(-8625 2325);
WIRE 16 -1 (-8600 2375)(-8600 2325);
WIRE 16 -1 (-7725 3075)(-8525 3075);
FORCEPROP 2 LAST SIG_NAME PD_CHE_CPU0_DIMM_SAA
J 0
(-8500 3085);
DISPLAY 0.489362 (-8500 3085);
WIRE 16 -1 (-7725 2625)(-8300 2625);
FORCEPROP 2 LAST SIG_NAME TP_CHE_CPU0_DIMM_RFU_6
J 0
(-8310 2635);
DISPLAY 0.489362 (-8310 2635);
FORCEPROP 2 LASTPROP $XRERR UNIQUE?
J 0
(-8540 2625);
DISPLAY 0.638298 (-8540 2625);
PAINT MONO (-8540 2625);
DISPLAY INVISIBLE (-8540 2625);
WIRE 16 -1 (-7725 3225)(-8375 3225);
FORCEPROP 2 LAST SIG_NAME M_E_CPU0_ALERT_N
J 0
(-8360 3235);
DISPLAY 0.489362 (-8360 3235);
WIRE 16 -1 (-7725 4575)(-8525 4575);
FORCEPROP 2 LAST SIG_NAME M_E_CPU0_SA_CS_N<0>
J 0
(-8475 4585);
DISPLAY 0.489362 (-8475 4585);
WIRE 16 -1 (-7725 4325)(-8525 4325);
FORCEPROP 2 LAST SIG_NAME M_E_CPU0_CLK_DP<0>
J 0
(-8475 4335);
DISPLAY 0.489362 (-8475 4335);
WIRE 16 -1 (-7725 4125)(-7925 4125);
WIRE 16 -1 (-7725 4075)(-7925 4075);
WIRE 16 -1 (-2000 5425)(-2300 5425);
WIRE 16 -1 (-2300 5425)(-2300 5375);
WIRE 16 -1 (-2000 5375)(-2300 5375);
WIRE 16 -1 (-2300 5375)(-2300 5325);
WIRE 16 -1 (-2000 5325)(-2300 5325);
WIRE 16 -1 (-2300 5325)(-2300 5275);
WIRE 16 -1 (-2000 5275)(-2300 5275);
WIRE 16 -1 (-2300 5275)(-2300 5225);
WIRE 16 -1 (-2000 5225)(-2300 5225);
WIRE 16 -1 (-2300 5225)(-2300 5175);
WIRE 16 -1 (-2000 5175)(-2300 5175);
WIRE 16 -1 (-2300 5175)(-2300 5125);
WIRE 16 -1 (-2000 5125)(-2300 5125);
WIRE 16 -1 (-2300 5125)(-2300 5075);
WIRE 16 -1 (-2000 5075)(-2300 5075);
WIRE 16 -1 (-2300 5075)(-2300 5025);
WIRE 16 -1 (-2000 5025)(-2300 5025);
WIRE 16 -1 (-2300 5025)(-2300 4975);
WIRE 16 -1 (-2000 4975)(-2300 4975);
WIRE 16 -1 (-2300 4975)(-2300 4925);
WIRE 16 -1 (-2000 4925)(-2300 4925);
WIRE 16 -1 (-2300 4925)(-2300 4875);
WIRE 16 -1 (-2000 4875)(-2300 4875);
WIRE 16 -1 (-2300 4875)(-2300 4825);
WIRE 16 -1 (-2000 4825)(-2300 4825);
WIRE 16 -1 (-2300 4825)(-2300 4775);
WIRE 16 -1 (-2000 4775)(-2300 4775);
WIRE 16 -1 (-2300 4775)(-2300 4725);
WIRE 16 -1 (-2000 4725)(-2300 4725);
WIRE 16 -1 (-2300 4725)(-2300 4675);
WIRE 16 -1 (-2000 4675)(-2300 4675);
WIRE 16 -1 (-2300 4675)(-2300 4625);
WIRE 16 -1 (-2000 4625)(-2300 4625);
WIRE 16 -1 (-2300 4625)(-2300 4575);
WIRE 16 -1 (-2000 4575)(-2300 4575);
WIRE 16 -1 (-2300 4575)(-2300 4525);
WIRE 16 -1 (-2000 4525)(-2300 4525);
WIRE 16 -1 (-2300 4525)(-2300 4475);
WIRE 16 -1 (-2000 4475)(-2300 4475);
WIRE 16 -1 (-2300 4475)(-2300 4425);
WIRE 16 -1 (-2000 4425)(-2300 4425);
WIRE 16 -1 (-2300 4425)(-2300 4375);
WIRE 16 -1 (-2000 4375)(-2300 4375);
WIRE 16 -1 (-2300 4375)(-2300 4325);
WIRE 16 -1 (-2000 4325)(-2300 4325);
WIRE 16 -1 (-2300 4325)(-2300 4275);
WIRE 16 -1 (-2000 4275)(-2300 4275);
WIRE 16 -1 (-2300 4275)(-2300 4225);
WIRE 16 -1 (-2000 4225)(-2300 4225);
WIRE 16 -1 (-2300 4225)(-2300 4175);
WIRE 16 -1 (-2000 4175)(-2300 4175);
WIRE 16 -1 (-2300 4175)(-2300 4125);
WIRE 16 -1 (-2000 4125)(-2300 4125);
WIRE 16 -1 (-2300 4125)(-2300 4075);
WIRE 16 -1 (-2000 4075)(-2300 4075);
WIRE 16 -1 (-2300 4075)(-2300 4025);
WIRE 16 -1 (-2000 4025)(-2300 4025);
WIRE 16 -1 (-2300 4025)(-2300 3975);
WIRE 16 -1 (-2000 3975)(-2300 3975);
WIRE 16 -1 (-2300 3975)(-2300 3925);
WIRE 16 -1 (-2000 3925)(-2300 3925);
WIRE 16 -1 (-2300 3925)(-2300 3875);
WIRE 16 -1 (-2000 3875)(-2300 3875);
WIRE 16 -1 (-2300 3875)(-2300 3825);
WIRE 16 -1 (-2000 3825)(-2300 3825);
WIRE 16 -1 (-2300 3825)(-2300 3775);
WIRE 16 -1 (-2000 3775)(-2300 3775);
WIRE 16 -1 (-2300 3775)(-2300 3725);
WIRE 16 -1 (-2000 3725)(-2300 3725);
WIRE 16 -1 (-2300 3725)(-2300 3675);
WIRE 16 -1 (-2000 3675)(-2300 3675);
WIRE 16 -1 (-2300 3675)(-2300 3625);
WIRE 16 -1 (-2000 3625)(-2300 3625);
WIRE 16 -1 (-2300 3625)(-2300 3575);
WIRE 16 -1 (-2000 3575)(-2300 3575);
WIRE 16 -1 (-2300 3575)(-2300 3525);
WIRE 16 -1 (-2000 3525)(-2300 3525);
WIRE 16 -1 (-2300 3525)(-2300 3475);
WIRE 16 -1 (-2000 3475)(-2300 3475);
WIRE 16 -1 (-2300 3475)(-2300 3425);
WIRE 16 -1 (-2000 3425)(-2300 3425);
WIRE 16 -1 (-2300 3425)(-2300 3375);
WIRE 16 -1 (-2000 3375)(-2300 3375);
WIRE 16 -1 (-2300 3375)(-2300 3325);
WIRE 16 -1 (-2000 3325)(-2300 3325);
WIRE 16 -1 (-2300 3325)(-2300 3275);
WIRE 16 -1 (-2000 3275)(-2300 3275);
WIRE 16 -1 (-2300 3275)(-2300 3225);
WIRE 16 -1 (-2000 3225)(-2300 3225);
WIRE 16 -1 (-2300 3225)(-2300 3175);
WIRE 16 -1 (-2000 3175)(-2300 3175);
WIRE 16 -1 (-2300 3175)(-2300 3125);
WIRE 16 -1 (-2000 3125)(-2300 3125);
WIRE 16 -1 (-2300 3125)(-2300 3075);
WIRE 16 -1 (-2000 3075)(-2300 3075);
WIRE 16 -1 (-2300 3075)(-2300 3025);
WIRE 16 -1 (-2000 3025)(-2300 3025);
WIRE 16 -1 (-2300 3025)(-2300 2975);
WIRE 16 -1 (-2000 2975)(-2300 2975);
WIRE 16 -1 (-2300 2975)(-2300 2925);
WIRE 16 -1 (-2000 2925)(-2300 2925);
WIRE 16 -1 (-2300 2925)(-2300 2875);
WIRE 16 -1 (-2000 2875)(-2300 2875);
WIRE 16 -1 (-2300 2875)(-2300 2825);
WIRE 16 -1 (-2000 2825)(-2300 2825);
WIRE 16 -1 (-2300 2825)(-2300 2775);
WIRE 16 -1 (-2000 2775)(-2300 2775);
WIRE 16 -1 (-2300 2775)(-2300 2725);
WIRE 16 -1 (-2000 2725)(-2300 2725);
WIRE 16 -1 (-2300 2725)(-2300 2675);
WIRE 16 -1 (-2000 2675)(-2300 2675);
WIRE 16 -1 (-2300 2675)(-2300 2625);
WIRE 16 -1 (-2000 2625)(-2300 2625);
WIRE 16 -1 (-2300 2625)(-2300 2575);
WIRE 16 -1 (-2000 2575)(-2300 2575);
WIRE 16 -1 (-2300 2575)(-2300 2525);
WIRE 16 -1 (-2000 2525)(-2300 2525);
WIRE 16 -1 (-2300 2525)(-2300 2475);
WIRE 16 -1 (-2000 2475)(-2300 2475);
WIRE 16 -1 (-2300 2475)(-2300 2425);
WIRE 16 -1 (-2000 2425)(-2300 2425);
WIRE 16 -1 (-2300 2425)(-2300 2375);
WIRE 16 -1 (-2300 2375)(-2300 2325);
WIRE 16 -1 (-2000 2375)(-2300 2375);
WIRE 16 -1 (-2000 2325)(-2300 2325);
WIRE 16 -1 (-2300 2325)(-2300 2225);
WIRE 16 -1 (-500 5575)(-500 5525);
WIRE 16 -1 (-500 5575)(-800 5575);
WIRE 16 -1 (-500 5525)(-500 5475);
WIRE 16 -1 (-500 5525)(-800 5525);
WIRE 16 -1 (-500 5475)(-500 5425);
WIRE 16 -1 (-500 5475)(-800 5475);
WIRE 16 -1 (-500 5425)(-500 5375);
WIRE 16 -1 (-500 5425)(-800 5425);
WIRE 16 -1 (-500 5375)(-500 5325);
WIRE 16 -1 (-500 5375)(-800 5375);
WIRE 16 -1 (-500 5325)(-500 5275);
WIRE 16 -1 (-500 5325)(-800 5325);
WIRE 16 -1 (-500 5275)(-500 5225);
WIRE 16 -1 (-500 5275)(-800 5275);
WIRE 16 -1 (-500 5225)(-500 5175);
WIRE 16 -1 (-500 5225)(-800 5225);
WIRE 16 -1 (-500 5175)(-500 5125);
WIRE 16 -1 (-500 5175)(-800 5175);
WIRE 16 -1 (-500 5125)(-800 5125);
WIRE 16 -1 (-500 5125)(-500 5075);
WIRE 16 -1 (-500 5075)(-500 5025);
WIRE 16 -1 (-500 5075)(-800 5075);
WIRE 16 -1 (-500 5025)(-500 4975);
WIRE 16 -1 (-500 5025)(-800 5025);
WIRE 16 -1 (-500 4975)(-500 4925);
WIRE 16 -1 (-500 4975)(-800 4975);
WIRE 16 -1 (-500 4925)(-500 4875);
WIRE 16 -1 (-500 4925)(-800 4925);
WIRE 16 -1 (-500 4875)(-500 4825);
WIRE 16 -1 (-500 4875)(-800 4875);
WIRE 16 -1 (-500 4825)(-500 4775);
WIRE 16 -1 (-500 4825)(-800 4825);
WIRE 16 -1 (-500 4775)(-500 4725);
WIRE 16 -1 (-500 4775)(-800 4775);
WIRE 16 -1 (-500 4725)(-500 4675);
WIRE 16 -1 (-500 4725)(-800 4725);
WIRE 16 -1 (-500 4675)(-500 4625);
WIRE 16 -1 (-500 4675)(-800 4675);
WIRE 16 -1 (-500 4625)(-500 4575);
WIRE 16 -1 (-500 4625)(-800 4625);
WIRE 16 -1 (-500 4575)(-500 4525);
WIRE 16 -1 (-500 4575)(-800 4575);
WIRE 16 -1 (-500 4525)(-500 4475);
WIRE 16 -1 (-500 4525)(-800 4525);
WIRE 16 -1 (-500 4475)(-500 4425);
WIRE 16 -1 (-500 4475)(-800 4475);
WIRE 16 -1 (-500 4425)(-500 4375);
WIRE 16 -1 (-500 4425)(-800 4425);
WIRE 16 -1 (-500 4375)(-500 4325);
WIRE 16 -1 (-500 4375)(-800 4375);
WIRE 16 -1 (-500 4325)(-500 4275);
WIRE 16 -1 (-500 4325)(-800 4325);
WIRE 16 -1 (-500 4275)(-500 4225);
WIRE 16 -1 (-500 4275)(-800 4275);
WIRE 16 -1 (-500 4225)(-500 4175);
WIRE 16 -1 (-500 4225)(-800 4225);
WIRE 16 -1 (-500 4175)(-500 4125);
WIRE 16 -1 (-500 4175)(-800 4175);
WIRE 16 -1 (-500 4125)(-800 4125);
WIRE 16 -1 (-500 4125)(-500 4075);
WIRE 16 -1 (-500 4075)(-500 4025);
WIRE 16 -1 (-500 4075)(-800 4075);
WIRE 16 -1 (-500 4025)(-500 3975);
WIRE 16 -1 (-500 4025)(-800 4025);
WIRE 16 -1 (-500 3975)(-500 3925);
WIRE 16 -1 (-500 3975)(-800 3975);
WIRE 16 -1 (-500 3925)(-500 3875);
WIRE 16 -1 (-500 3925)(-800 3925);
WIRE 16 -1 (-500 3875)(-500 3825);
WIRE 16 -1 (-500 3875)(-800 3875);
WIRE 16 -1 (-500 3825)(-500 3775);
WIRE 16 -1 (-500 3825)(-800 3825);
WIRE 16 -1 (-500 3775)(-500 3725);
WIRE 16 -1 (-500 3775)(-800 3775);
WIRE 16 -1 (-500 3725)(-500 3675);
WIRE 16 -1 (-500 3725)(-800 3725);
WIRE 16 -1 (-500 3675)(-500 3625);
WIRE 16 -1 (-500 3675)(-800 3675);
WIRE 16 -1 (-500 3625)(-500 3575);
WIRE 16 -1 (-500 3625)(-800 3625);
WIRE 16 -1 (-500 3575)(-500 3525);
WIRE 16 -1 (-500 3575)(-800 3575);
WIRE 16 -1 (-500 3525)(-500 3475);
WIRE 16 -1 (-500 3525)(-800 3525);
WIRE 16 -1 (-500 3475)(-500 3425);
WIRE 16 -1 (-500 3475)(-800 3475);
WIRE 16 -1 (-500 3425)(-500 3375);
WIRE 16 -1 (-500 3425)(-800 3425);
WIRE 16 -1 (-500 3375)(-500 3325);
WIRE 16 -1 (-500 3375)(-800 3375);
WIRE 16 -1 (-500 3325)(-500 3275);
WIRE 16 -1 (-500 3325)(-800 3325);
WIRE 16 -1 (-500 3275)(-500 3225);
WIRE 16 -1 (-500 3275)(-800 3275);
WIRE 16 -1 (-500 3225)(-500 3175);
WIRE 16 -1 (-500 3225)(-800 3225);
WIRE 16 -1 (-500 3175)(-500 3125);
WIRE 16 -1 (-500 3175)(-800 3175);
WIRE 16 -1 (-500 3125)(-500 3075);
WIRE 16 -1 (-500 3125)(-800 3125);
WIRE 16 -1 (-500 3075)(-800 3075);
WIRE 16 -1 (-500 3075)(-500 3025);
WIRE 16 -1 (-500 3025)(-500 2975);
WIRE 16 -1 (-500 3025)(-800 3025);
WIRE 16 -1 (-500 2975)(-500 2925);
WIRE 16 -1 (-500 2975)(-800 2975);
WIRE 16 -1 (-500 2925)(-500 2875);
WIRE 16 -1 (-500 2925)(-800 2925);
WIRE 16 -1 (-500 2875)(-500 2825);
WIRE 16 -1 (-500 2875)(-800 2875);
WIRE 16 -1 (-500 2825)(-500 2775);
WIRE 16 -1 (-500 2825)(-800 2825);
WIRE 16 -1 (-500 2775)(-500 2725);
WIRE 16 -1 (-500 2775)(-800 2775);
WIRE 16 -1 (-500 2725)(-500 2675);
WIRE 16 -1 (-500 2725)(-800 2725);
WIRE 16 -1 (-500 2675)(-500 2625);
WIRE 16 -1 (-500 2675)(-800 2675);
WIRE 16 -1 (-500 2625)(-500 2575);
WIRE 16 -1 (-500 2625)(-800 2625);
WIRE 16 -1 (-500 2575)(-500 2525);
WIRE 16 -1 (-500 2575)(-800 2575);
WIRE 16 -1 (-500 2525)(-500 2475);
WIRE 16 -1 (-500 2525)(-800 2525);
WIRE 16 -1 (-500 2475)(-500 2425);
WIRE 16 -1 (-500 2475)(-800 2475);
WIRE 16 -1 (-500 2425)(-500 2325);
WIRE 16 -1 (-500 2425)(-800 2425);
WIRE 16 -1 (-500 2325)(-500 2275);
WIRE 16 -1 (-500 2325)(-800 2325);
WIRE 16 -1 (-500 2275)(-500 2225);
WIRE 16 -1 (-500 2275)(-800 2275);
WIRE 16 -1 (-500 2225)(-500 2050);
WIRE 16 -1 (-500 2225)(-800 2225);
WIRE 16 -1 (-2300 5475)(-2000 5475);
WIRE 16 -1 (-2300 5525)(-2300 5475);
WIRE 16 -1 (-2000 5525)(-2300 5525);
WIRE 16 -1 (-2300 5525)(-2300 5575);
WIRE 16 -1 (-2000 5575)(-2300 5575);
WIRE 16 -1 (-2300 5575)(-2300 6250);
WIRE 16 -1 (-2400 6250)(-2300 6250);
WIRE 16 -1 (-2400 6250)(-2975 6250);
WIRE 16 -1 (-2400 6250)(-2400 6150);
WIRE 16 -1 (-2975 6250)(-2975 6325);
WIRE 16 -1 (-2975 6150)(-2975 6250);
WIRE 16 -1 (-3725 4075)(-3875 4075);
WIRE 16 -1 (-6525 4975)(-6325 4975);
WIRE 16 -1 (-3875 4625)(-3525 4625);
WIRE 16 -1 (-3875 4675)(-3725 4675);
WIRE 16 -1 (-3875 3625)(-3725 3625);
WIRE 16 -1 (-3875 3575)(-3525 3575);
WIRE 16 -1 (-3725 4575)(-3875 4575);
WIRE 16 -1 (-3875 4525)(-3525 4525);
WIRE 16 -1 (-3875 3375)(-3525 3375);
WIRE 16 -1 (-3725 4475)(-3875 4475);
WIRE 16 -1 (-3725 3325)(-3875 3325);
WIRE 16 -1 (-3875 3275)(-3525 3275);
WIRE 16 -1 (-3875 4325)(-3525 4325);
WIRE 16 -1 (-3875 3225)(-3725 3225);
WIRE 16 -1 (-3875 3175)(-3525 3175);
WIRE 16 -1 (-3875 4275)(-3725 4275);
WIRE 16 -1 (-3875 4225)(-3525 4225);
WIRE 16 -1 (-3725 3125)(-3875 3125);
WIRE 16 -1 (-3875 3075)(-3525 3075);
WIRE 16 -1 (-3725 4175)(-3875 4175);
WIRE 16 -1 (-3875 4125)(-3525 4125);
WIRE 16 -1 (-3725 3025)(-3875 3025);
WIRE 16 -1 (-3875 2975)(-3525 2975);
WIRE 16 -1 (-3875 4025)(-3525 4025);
WIRE 16 -1 (-3725 2925)(-3875 2925);
WIRE 16 -1 (-3875 2875)(-3525 2875);
WIRE 16 -1 (-3725 3975)(-3875 3975);
WIRE 16 -1 (-3875 3925)(-3525 3925);
WIRE 16 -1 (-3875 2825)(-3725 2825);
WIRE 16 -1 (-3875 2775)(-3525 2775);
WIRE 16 -1 (-3875 3875)(-3725 3875);
WIRE 16 -1 (-3875 3825)(-3525 3825);
WIRE 16 -1 (-3725 2725)(-3875 2725);
WIRE 16 -1 (-3875 2675)(-3525 2675);
WIRE 16 -1 (-3725 3775)(-3875 3775);
WIRE 16 -1 (-3875 3725)(-3525 3725);
WIRE 16 -1 (-3725 3425)(-3875 3425);
WIRE 16 -1 (-3875 3475)(-3525 3475);
WIRE 16 -1 (-3725 3525)(-3875 3525);
WIRE 16 -1 (-3725 4375)(-3875 4375);
WIRE 16 -1 (-3875 4425)(-3525 4425);
WIRE 16 -1 (-6325 5125)(-6525 5125);
WIRE 16 -1 (-7725 5075)(-7925 5075);
WIRE 16 -1 (-7725 5325)(-7925 5325);
WIRE 16 -1 (-6325 5475)(-6525 5475);
WIRE 16 -1 (-6325 5275)(-6525 5275);
WIRE 16 -1 (-7725 2325)(-8300 2325);
FORCEPROP 2 LAST SIG_NAME TP_CHE_CPU0_DIMM_RFU_0
J 0
(-8310 2335);
DISPLAY 0.489362 (-8310 2335);
FORCEPROP 2 LASTPROP $XRERR UNIQUE?
J 0
(-8540 2325);
DISPLAY 0.638298 (-8540 2325);
PAINT MONO (-8540 2325);
DISPLAY INVISIBLE (-8540 2325);
WIRE 16 -1 (-7725 2375)(-8300 2375);
FORCEPROP 2 LAST SIG_NAME TP_CHE_CPU0_DIMM_RFU_1
J 0
(-8310 2385);
DISPLAY 0.489362 (-8310 2385);
FORCEPROP 2 LASTPROP $XRERR UNIQUE?
J 0
(-8540 2375);
DISPLAY 0.638298 (-8540 2375);
PAINT MONO (-8540 2375);
DISPLAY INVISIBLE (-8540 2375);
WIRE 16 -1 (-7725 2425)(-8300 2425);
FORCEPROP 2 LAST SIG_NAME TP_CHE_CPU0_DIMM_RFU_2
J 0
(-8310 2435);
DISPLAY 0.489362 (-8310 2435);
FORCEPROP 2 LASTPROP $XRERR UNIQUE?
J 0
(-8540 2425);
DISPLAY 0.638298 (-8540 2425);
PAINT MONO (-8540 2425);
DISPLAY INVISIBLE (-8540 2425);
WIRE 16 -1 (-7725 2475)(-8300 2475);
FORCEPROP 2 LAST SIG_NAME TP_CHE_CPU0_DIMM_RFU_3
J 0
(-8310 2485);
DISPLAY 0.489362 (-8310 2485);
FORCEPROP 2 LASTPROP $XRERR UNIQUE?
J 0
(-8540 2475);
DISPLAY 0.638298 (-8540 2475);
PAINT MONO (-8540 2475);
DISPLAY INVISIBLE (-8540 2475);
WIRE 16 -1 (-7725 2525)(-8300 2525);
FORCEPROP 2 LAST SIG_NAME TP_CHE_CPU0_DIMM_RFU_4
J 0
(-8310 2535);
DISPLAY 0.489362 (-8310 2535);
FORCEPROP 2 LASTPROP $XRERR UNIQUE?
J 0
(-8540 2525);
DISPLAY 0.638298 (-8540 2525);
PAINT MONO (-8540 2525);
DISPLAY INVISIBLE (-8540 2525);
WIRE 16 -1 (-7725 2575)(-8300 2575);
FORCEPROP 2 LAST SIG_NAME TP_CHE_CPU0_DIMM_RFU_5
J 0
(-8310 2585);
DISPLAY 0.489362 (-8310 2585);
FORCEPROP 2 LASTPROP $XRERR UNIQUE?
J 0
(-8540 2575);
DISPLAY 0.638298 (-8540 2575);
PAINT MONO (-8540 2575);
DISPLAY INVISIBLE (-8540 2575);
WIRE 16 -1 (-7725 3275)(-8375 3275);
FORCEPROP 2 LAST SIG_NAME M_E_CPU0_RESET_N
J 0
(-8360 3285);
DISPLAY 0.489362 (-8360 3285);
WIRE 16 -1 (-7725 4725)(-8525 4725);
FORCEPROP 2 LAST SIG_NAME M_E_CPU0_SB_PAR
J 0
(-8475 4735);
DISPLAY 0.489362 (-8475 4735);
WIRE 16 -1 (-7725 4775)(-8525 4775);
FORCEPROP 2 LAST SIG_NAME M_E_CPU0_SA_PAR
J 0
(-8475 4785);
DISPLAY 0.489362 (-8475 4785);
WIRE 16 -1 (-7725 2125)(-8525 2125);
FORCEPROP 2 LAST SIG_NAME M_E_CPU0_SB_RSP<0>
J 0
(-8475 2135);
DISPLAY 0.489362 (-8475 2135);
WIRE 16 -1 (-7725 2175)(-8525 2175);
FORCEPROP 2 LAST SIG_NAME M_E_CPU0_SA_RSP<0>
J 0
(-8475 2185);
DISPLAY 0.489362 (-8475 2185);
WIRE 16 -1 (-6325 2375)(-6525 2375);
WIRE 16 -1 (-6325 2425)(-6525 2425);
WIRE 16 -1 (-6325 2475)(-6525 2475);
WIRE 16 -1 (-6525 2525)(-6325 2525);
WIRE 16 -1 (-6325 2575)(-6525 2575);
WIRE 16 -1 (-6325 2625)(-6525 2625);
WIRE 16 -1 (-6325 2675)(-6525 2675);
WIRE 16 -1 (-6525 2725)(-6325 2725);
WIRE 16 -1 (-6325 2775)(-6525 2775);
WIRE 16 -1 (-6325 2825)(-6525 2825);
WIRE 16 -1 (-6325 2875)(-6525 2875);
WIRE 16 -1 (-6525 2925)(-6325 2925);
WIRE 16 -1 (-6325 2975)(-6525 2975);
WIRE 16 -1 (-6325 3025)(-6525 3025);
WIRE 16 -1 (-6325 3075)(-6525 3075);
WIRE 16 -1 (-6525 3125)(-6325 3125);
WIRE 16 -1 (-6325 3175)(-6525 3175);
WIRE 16 -1 (-6325 3225)(-6525 3225);
WIRE 16 -1 (-6325 3275)(-6525 3275);
WIRE 16 -1 (-6525 3325)(-6325 3325);
WIRE 16 -1 (-6325 3375)(-6525 3375);
WIRE 16 -1 (-6325 3425)(-6525 3425);
WIRE 16 -1 (-6325 3475)(-6525 3475);
WIRE 16 -1 (-6525 3525)(-6325 3525);
WIRE 16 -1 (-6325 3575)(-6525 3575);
WIRE 16 -1 (-6325 3625)(-6525 3625);
WIRE 16 -1 (-6325 3675)(-6525 3675);
WIRE 16 -1 (-6525 3725)(-6325 3725);
WIRE 16 -1 (-6325 3775)(-6525 3775);
WIRE 16 -1 (-6325 3825)(-6525 3825);
WIRE 16 -1 (-6325 3875)(-6525 3875);
WIRE 16 -1 (-6525 3925)(-6325 3925);
WIRE 16 -1 (-6325 4025)(-6525 4025);
WIRE 16 -1 (-6325 4075)(-6525 4075);
WIRE 16 -1 (-6325 4125)(-6525 4125);
WIRE 16 -1 (-6525 4175)(-6325 4175);
WIRE 16 -1 (-6325 4225)(-6525 4225);
WIRE 16 -1 (-6325 4275)(-6525 4275);
WIRE 16 -1 (-6325 4325)(-6525 4325);
WIRE 16 -1 (-6525 4375)(-6325 4375);
WIRE 16 -1 (-6325 4425)(-6525 4425);
WIRE 16 -1 (-6325 4475)(-6525 4475);
WIRE 16 -1 (-6325 4525)(-6525 4525);
WIRE 16 -1 (-6525 4575)(-6325 4575);
WIRE 16 -1 (-6325 4625)(-6525 4625);
WIRE 16 -1 (-6325 4675)(-6525 4675);
WIRE 16 -1 (-6325 4725)(-6525 4725);
WIRE 16 -1 (-6525 4775)(-6325 4775);
WIRE 16 -1 (-6325 4825)(-6525 4825);
WIRE 16 -1 (-6325 4875)(-6525 4875);
WIRE 16 -1 (-6325 4925)(-6525 4925);
WIRE 16 -1 (-6325 5025)(-6525 5025);
WIRE 16 -1 (-6325 5075)(-6525 5075);
WIRE 16 -1 (-6525 5175)(-6325 5175);
WIRE 16 -1 (-6325 5225)(-6525 5225);
WIRE 16 -1 (-6325 5325)(-6525 5325);
WIRE 16 -1 (-6525 5375)(-6325 5375);
WIRE 16 -1 (-6325 5425)(-6525 5425);
WIRE 16 -1 (-6325 5525)(-6525 5525);
WIRE 16 -1 (-7725 4475)(-8525 4475);
FORCEPROP 2 LAST SIG_NAME M_E_CPU0_SB_CS_N<1>
J 0
(-8475 4485);
DISPLAY 0.489362 (-8475 4485);
WIRE 16 -1 (-7725 4625)(-8525 4625);
FORCEPROP 2 LAST SIG_NAME M_E_CPU0_SA_CS_N<1>
J 0
(-8475 4635);
DISPLAY 0.489362 (-8475 4635);
WIRE 16 -1 (-7725 4425)(-8525 4425);
FORCEPROP 2 LAST SIG_NAME M_E_CPU0_SB_CS_N<0>
J 0
(-8475 4435);
DISPLAY 0.489362 (-8475 4435);
WIRE 16 -1 (-7725 4275)(-8525 4275);
FORCEPROP 2 LAST SIG_NAME M_E_CPU0_CLK_DN<0>
J 0
(-8475 4285);
DISPLAY 0.489362 (-8475 4285);
WIRE 16 -1 (-7725 3375)(-7925 3375);
WIRE 16 -1 (-7725 3425)(-7925 3425);
WIRE 16 -1 (-7725 3475)(-7925 3475);
WIRE 16 -1 (-7725 3525)(-7925 3525);
WIRE 16 -1 (-7725 3575)(-7925 3575);
WIRE 16 -1 (-7725 3625)(-7925 3625);
WIRE 16 -1 (-7725 3675)(-7925 3675);
WIRE 16 -1 (-7725 3825)(-7925 3825);
WIRE 16 -1 (-7725 3925)(-7925 3925);
WIRE 16 -1 (-7725 3975)(-7925 3975);
WIRE 16 -1 (-7725 5175)(-7925 5175);
WIRE 16 -1 (-7725 5575)(-7925 5575);
WIRE 16 -1 (-7725 5125)(-7925 5125);
WIRE 16 -1 (-7725 5525)(-7925 5525);
WIRE 16 -1 (-7725 5475)(-7925 5475);
WIRE 16 -1 (-7725 5025)(-7925 5025);
WIRE 16 -1 (-7725 5425)(-7925 5425);
WIRE 16 -1 (-7725 4975)(-7925 4975);
WIRE 16 -1 (-7725 5375)(-7925 5375);
WIRE 16 -1 (-7725 4925)(-7925 4925);
WIRE 16 -1 (-7725 4875)(-7925 4875);
WIRE 16 -1 (-7725 5275)(-7925 5275);
WIRE 16 -1 (-7725 3725)(-7925 3725);
WIRE 16 -1 (-7725 3875)(-7925 3875);
WIRE 16 -1 (-7725 4025)(-7925 4025);
WIRE 16 -1 (-7725 4175)(-7925 4175);
WIRE 16 -1 (-6525 5575)(-6325 5575);
WIRE 16 -1 (-9175 2325)(-8825 2325);
FORCEPROP 2 LAST SIG_NAME PWRGD_CHAF_CPU0
J 0
(-9160 2335);
DISPLAY 0.489362 (-9160 2335);
WIRE 16 -1 (-6650 1600)(-6650 1525);
WIRE 16 -1 (-6650 1600)(-7375 1600);
FORCEPROP 2 LAST SIG_NAME PD_CHE_CPU0_DIMM_SAA
J 0
(-7360 1610);
DISPLAY 0.489362 (-7360 1610);
WIRE 16 -1 (-2400 5825)(-2975 5825);
WIRE 16 -1 (-2400 5825)(-2400 5950);
WIRE 16 -1 (-2975 5825)(-2975 5950);
WIRE 16 -1 (-2975 5825)(-2975 5750);
DOT 1 (-2975 6250);
DOT 1 (-2400 6250);
DOT 1 (-2975 5825);
DOT 1 (-8600 2325);
DOT 1 (-8775 3525);
DOT 1 (-2300 5525);
DOT 1 (-2300 5575);
DOT 1 (-2300 2325);
DOT 1 (-2300 2475);
DOT 1 (-2300 2425);
DOT 1 (-2300 2375);
DOT 1 (-2300 2525);
DOT 1 (-2300 2575);
DOT 1 (-2300 2675);
DOT 1 (-2300 2625);
DOT 1 (-2300 2725);
DOT 1 (-2300 2825);
DOT 1 (-2300 2775);
DOT 1 (-2300 2875);
DOT 1 (-2300 2975);
DOT 1 (-2300 2925);
DOT 1 (-2300 3025);
DOT 1 (-2300 3075);
DOT 1 (-2300 3125);
DOT 1 (-2300 3225);
DOT 1 (-2300 3175);
DOT 1 (-2300 3275);
DOT 1 (-2300 3325);
DOT 1 (-2300 3375);
DOT 1 (-2300 3475);
DOT 1 (-2300 3425);
DOT 1 (-2300 3575);
DOT 1 (-2300 3525);
DOT 1 (-2300 3625);
DOT 1 (-2300 3675);
DOT 1 (-2300 3725);
DOT 1 (-2300 3875);
DOT 1 (-2300 3825);
DOT 1 (-2300 3775);
DOT 1 (-2300 3975);
DOT 1 (-2300 3925);
DOT 1 (-2300 4025);
DOT 1 (-2300 4125);
DOT 1 (-2300 4175);
DOT 1 (-2300 4225);
DOT 1 (-500 2225);
DOT 1 (-500 2275);
DOT 1 (-500 2325);
DOT 1 (-500 2425);
DOT 1 (-500 2475);
DOT 1 (-500 2575);
DOT 1 (-500 2525);
DOT 1 (-500 2625);
DOT 1 (-500 2725);
DOT 1 (-500 2675);
DOT 1 (-500 2825);
DOT 1 (-500 2775);
DOT 1 (-500 2875);
DOT 1 (-500 2925);
DOT 1 (-500 2975);
DOT 1 (-500 3075);
DOT 1 (-500 3025);
DOT 1 (-500 3125);
DOT 1 (-500 3225);
DOT 1 (-500 3175);
DOT 1 (-500 3275);
DOT 1 (-500 3325);
DOT 1 (-500 3375);
DOT 1 (-500 3475);
DOT 1 (-500 3425);
DOT 1 (-500 3525);
DOT 1 (-500 3575);
DOT 1 (-500 3625);
DOT 1 (-500 3675);
DOT 1 (-500 3725);
DOT 1 (-500 3775);
DOT 1 (-500 3825);
DOT 1 (-500 3875);
DOT 1 (-500 3975);
DOT 1 (-500 3925);
DOT 1 (-500 4025);
DOT 1 (-500 4075);
DOT 1 (-500 4125);
DOT 1 (-500 4225);
DOT 1 (-500 4175);
DOT 1 (-500 4275);
DOT 1 (-2300 4275);
DOT 1 (-2300 4375);
DOT 1 (-2300 4325);
DOT 1 (-2300 4475);
DOT 1 (-2300 4425);
DOT 1 (-2300 4575);
DOT 1 (-2300 4625);
DOT 1 (-2300 4775);
DOT 1 (-2300 4725);
DOT 1 (-2300 4675);
DOT 1 (-2300 4875);
DOT 1 (-2300 4825);
DOT 1 (-2300 4925);
DOT 1 (-2300 4975);
DOT 1 (-2300 5075);
DOT 1 (-2300 5125);
DOT 1 (-2300 5175);
DOT 1 (-2300 5225);
DOT 1 (-2300 5375);
DOT 1 (-2300 5325);
DOT 1 (-500 4325);
DOT 1 (-500 4375);
DOT 1 (-500 4425);
DOT 1 (-500 4525);
DOT 1 (-500 4475);
DOT 1 (-500 4625);
DOT 1 (-500 4575);
DOT 1 (-500 4675);
DOT 1 (-500 4725);
DOT 1 (-500 4775);
DOT 1 (-500 4875);
DOT 1 (-500 4825);
DOT 1 (-500 4925);
DOT 1 (-500 4975);
DOT 1 (-500 5025);
DOT 1 (-500 5125);
DOT 1 (-500 5075);
DOT 1 (-500 5175);
DOT 1 (-500 5275);
DOT 1 (-500 5225);
DOT 1 (-500 5375);
DOT 1 (-500 5325);
DOT 1 (-500 5425);
DOT 1 (-500 5525);
DOT 1 (-500 5475);
DOT 1 (-2300 4525);
DOT 1 (-2300 4075);
DOT 1 (-2300 5025);
DOT 1 (-2300 5275);
QUIT
